FILE_TYPE = MACRO_DRAWING;
SET COLOR_WIRE YELLOW;
SET COLOR_PROP ORANGE;
SET COLOR_DOT WHITE;
SET COLOR_ARC YELLOW;
SET COLOR_BODY GREEN;
SET COLOR_NOTE PURPLE;
SET PROP_DISPLAY VALUE;
SET PAGE_NUMBER P317;
FORCEADD OFFPAGE..1
(-3200 -1250);
FORCEPROP 2 LAST $XR0 287 
J 0
(-3452 -1250);
DISPLAY 0.638298 (-3452 -1250);
PAINT MONO (-3452 -1250);
FORCEPROP 2 LAST CDS_LIB standard
J 0
(-3200 -1250);
DISPLAY INVISIBLE (-3200 -1250);
FORCEPROP 1 LAST OFFPAGE TRUE
J 0
(-2875 -1375);
DISPLAY 0.872340 (-2875 -1375);
PAINT AQUA (-2875 -1375);
DISPLAY INVISIBLE (-2875 -1375);
FORCEPROP 1 LAST COMMENT_BODY TRUE
J 0
(-3075 -1350);
DISPLAY 0.872340 (-3075 -1350);
PAINT GREEN (-3075 -1350);
DISPLAY INVISIBLE (-3075 -1350);
FORCEPROP 2 LAST PATH I1
J 0
(-3450 -1200);
DISPLAY 0.680851 (-3450 -1200);
DISPLAY INVISIBLE (-3450 -1200);
FORCEADD OFFPAGE..1
(-3200 -250);
FORCEPROP 2 LAST $XR0 276 
J 0
(-3452 -250);
DISPLAY 0.638298 (-3452 -250);
PAINT MONO (-3452 -250);
FORCEPROP 2 LAST CDS_LIB standard
J 0
(-3200 -250);
DISPLAY INVISIBLE (-3200 -250);
FORCEPROP 1 LAST OFFPAGE TRUE
J 0
(-2875 -375);
DISPLAY 0.872340 (-2875 -375);
PAINT AQUA (-2875 -375);
DISPLAY INVISIBLE (-2875 -375);
FORCEPROP 1 LAST COMMENT_BODY TRUE
J 0
(-3075 -350);
DISPLAY 0.872340 (-3075 -350);
PAINT GREEN (-3075 -350);
DISPLAY INVISIBLE (-3075 -350);
FORCEPROP 2 LAST PATH I10
J 0
(-3450 -200);
DISPLAY 0.680851 (-3450 -200);
DISPLAY INVISIBLE (-3450 -200);
FORCEADD OFFPAGE..1
(-3200 -350);
FORCEPROP 2 LAST $XR0 287 
J 0
(-3452 -350);
DISPLAY 0.638298 (-3452 -350);
PAINT MONO (-3452 -350);
FORCEPROP 2 LAST CDS_LIB standard
J 0
(-3200 -350);
DISPLAY INVISIBLE (-3200 -350);
FORCEPROP 1 LAST OFFPAGE TRUE
J 0
(-2875 -475);
DISPLAY 0.872340 (-2875 -475);
PAINT AQUA (-2875 -475);
DISPLAY INVISIBLE (-2875 -475);
FORCEPROP 1 LAST COMMENT_BODY TRUE
J 0
(-3075 -450);
DISPLAY 0.872340 (-3075 -450);
PAINT GREEN (-3075 -450);
DISPLAY INVISIBLE (-3075 -450);
FORCEPROP 2 LAST PATH I11
J 0
(-3450 -300);
DISPLAY 0.680851 (-3450 -300);
DISPLAY INVISIBLE (-3450 -300);
FORCEADD OFFPAGE..1
(-3200 -200);
FORCEPROP 2 LAST $XR0 276 
J 0
(-3452 -200);
DISPLAY 0.638298 (-3452 -200);
PAINT MONO (-3452 -200);
FORCEPROP 2 LAST CDS_LIB standard
J 0
(-3200 -200);
DISPLAY INVISIBLE (-3200 -200);
FORCEPROP 1 LAST OFFPAGE TRUE
J 0
(-2875 -325);
DISPLAY 0.872340 (-2875 -325);
PAINT AQUA (-2875 -325);
DISPLAY INVISIBLE (-2875 -325);
FORCEPROP 1 LAST COMMENT_BODY TRUE
J 0
(-3075 -300);
DISPLAY 0.872340 (-3075 -300);
PAINT GREEN (-3075 -300);
DISPLAY INVISIBLE (-3075 -300);
FORCEPROP 2 LAST PATH I12
J 0
(-3450 -150);
DISPLAY 0.680851 (-3450 -150);
DISPLAY INVISIBLE (-3450 -150);
FORCEADD UNIVERSAL_GND..1
(-2100 -1650);
FORCEPROP 3 LASTPIN (-2100 -1600) SIG_NAME GND\g
J 0
(-2090 -1590);
DISPLAY 0.659574 (-2090 -1590);
PAINT MONO (-2090 -1590);
DISPLAY INVISIBLE (-2090 -1590);
FORCEPROP 2 LAST CDS_LIB pure_quanta_power
J 0
(-2100 -1650);
DISPLAY INVISIBLE (-2100 -1650);
FORCEPROP 1 LAST HDL_POWER GND
J 1
(-2075 -1725);
DISPLAY 0.872340 (-2075 -1725);
PAINT GREEN (-2075 -1725);
DISPLAY INVISIBLE (-2075 -1725);
FORCEPROP 1 LAST PATH I13
J 0
(-2025 -1650);
DISPLAY 0.872340 (-2025 -1650);
PAINT AQUA (-2025 -1650);
DISPLAY INVISIBLE (-2025 -1650);
FORCEADD OFFPAGE..5
(-3200 -100);
FORCEPROP 2 LAST $XR0 286 
J 0
(-3455 -100);
DISPLAY 0.638298 (-3455 -100);
PAINT MONO (-3455 -100);
FORCEPROP 2 LAST CDS_LIB standard
J 0
(-3200 -100);
DISPLAY INVISIBLE (-3200 -100);
FORCEPROP 1 LAST OFFPAGE TRUE
J 0
(-2875 -225);
DISPLAY 0.872340 (-2875 -225);
PAINT AQUA (-2875 -225);
DISPLAY INVISIBLE (-2875 -225);
FORCEPROP 1 LAST COMMENT_BODY TRUE
J 0
(-3100 -175);
DISPLAY 1.170213 (-3100 -175);
PAINT GREEN (-3100 -175);
DISPLAY INVISIBLE (-3100 -175);
FORCEPROP 2 LAST PATH I14
J 0
(-3475 -50);
DISPLAY 0.680851 (-3475 -50);
DISPLAY INVISIBLE (-3475 -50);
FORCEADD OFFPAGE..2
R 2
(-3200 -50);
FORCEPROP 2 LAST $XR0 286 
J 0
(-3455 -50);
DISPLAY 0.638298 (-3455 -50);
PAINT MONO (-3455 -50);
FORCEPROP 2 LAST CDS_LIB standard
J 0
(-3200 -50);
DISPLAY INVISIBLE (-3200 -50);
FORCEPROP 1 LAST OFFPAGE TRUE
J 2
(-3525 -175);
DISPLAY 0.872340 (-3525 -175);
PAINT AQUA (-3525 -175);
DISPLAY INVISIBLE (-3525 -175);
FORCEPROP 1 LAST COMMENT_BODY TRUE
J 2
(-3155 -145);
DISPLAY 0.872340 (-3155 -145);
PAINT GREEN (-3155 -145);
DISPLAY INVISIBLE (-3155 -145);
FORCEPROP 2 LAST PATH I15
J 0
(-3475 0);
DISPLAY 0.680851 (-3475 0);
DISPLAY INVISIBLE (-3475 0);
FORCEADD OFFPAGE..5
(-3200 50);
FORCEPROP 2 LAST $XR0 275 
J 0
(-3455 50);
DISPLAY 0.638298 (-3455 50);
PAINT MONO (-3455 50);
FORCEPROP 2 LAST CDS_LIB standard
J 0
(-3200 50);
DISPLAY INVISIBLE (-3200 50);
FORCEPROP 1 LAST OFFPAGE TRUE
J 0
(-2875 -75);
DISPLAY 0.872340 (-2875 -75);
PAINT AQUA (-2875 -75);
DISPLAY INVISIBLE (-2875 -75);
FORCEPROP 1 LAST COMMENT_BODY TRUE
J 0
(-3100 -25);
DISPLAY 1.170213 (-3100 -25);
PAINT GREEN (-3100 -25);
DISPLAY INVISIBLE (-3100 -25);
FORCEPROP 2 LAST PATH I16
J 0
(-3475 100);
DISPLAY 0.680851 (-3475 100);
DISPLAY INVISIBLE (-3475 100);
FORCEADD OFFPAGE..2
R 2
(-3200 100);
FORCEPROP 2 LAST $XR0 275 
J 0
(-3455 100);
DISPLAY 0.638298 (-3455 100);
PAINT MONO (-3455 100);
FORCEPROP 2 LAST CDS_LIB standard
J 0
(-3200 100);
DISPLAY INVISIBLE (-3200 100);
FORCEPROP 1 LAST OFFPAGE TRUE
J 2
(-3525 -25);
DISPLAY 0.872340 (-3525 -25);
PAINT AQUA (-3525 -25);
DISPLAY INVISIBLE (-3525 -25);
FORCEPROP 1 LAST COMMENT_BODY TRUE
J 2
(-3155 5);
DISPLAY 0.872340 (-3155 5);
PAINT GREEN (-3155 5);
DISPLAY INVISIBLE (-3155 5);
FORCEPROP 2 LAST PATH I17
J 0
(-3475 150);
DISPLAY 0.680851 (-3475 150);
DISPLAY INVISIBLE (-3475 150);
FORCEADD OFFPAGE..1
(-3200 350);
FORCEPROP 2 LAST $XR0 287 
J 0
(-3452 350);
DISPLAY 0.638298 (-3452 350);
PAINT MONO (-3452 350);
FORCEPROP 2 LAST CDS_LIB standard
J 0
(-3200 350);
DISPLAY INVISIBLE (-3200 350);
FORCEPROP 1 LAST OFFPAGE TRUE
J 0
(-2875 225);
DISPLAY 0.872340 (-2875 225);
PAINT AQUA (-2875 225);
DISPLAY INVISIBLE (-2875 225);
FORCEPROP 1 LAST COMMENT_BODY TRUE
J 0
(-3075 250);
DISPLAY 0.872340 (-3075 250);
PAINT GREEN (-3075 250);
DISPLAY INVISIBLE (-3075 250);
FORCEPROP 2 LAST PATH I18
J 0
(-3450 400);
DISPLAY 0.680851 (-3450 400);
DISPLAY INVISIBLE (-3450 400);
FORCEADD OFFPAGE..1
(-3200 400);
FORCEPROP 2 LAST $XR0 287 
J 0
(-3452 400);
DISPLAY 0.638298 (-3452 400);
PAINT MONO (-3452 400);
FORCEPROP 2 LAST CDS_LIB standard
J 0
(-3200 400);
DISPLAY INVISIBLE (-3200 400);
FORCEPROP 1 LAST OFFPAGE TRUE
J 0
(-2875 275);
DISPLAY 0.872340 (-2875 275);
PAINT AQUA (-2875 275);
DISPLAY INVISIBLE (-2875 275);
FORCEPROP 1 LAST COMMENT_BODY TRUE
J 0
(-3075 300);
DISPLAY 0.872340 (-3075 300);
PAINT GREEN (-3075 300);
DISPLAY INVISIBLE (-3075 300);
FORCEPROP 2 LAST PATH I19
J 0
(-3450 450);
DISPLAY 0.680851 (-3450 450);
DISPLAY INVISIBLE (-3450 450);
FORCEADD OFFPAGE..1
(-3200 -1200);
FORCEPROP 2 LAST $XR0 287 
J 0
(-3452 -1200);
DISPLAY 0.638298 (-3452 -1200);
PAINT MONO (-3452 -1200);
FORCEPROP 2 LAST CDS_LIB standard
J 0
(-3200 -1200);
DISPLAY INVISIBLE (-3200 -1200);
FORCEPROP 1 LAST OFFPAGE TRUE
J 0
(-2875 -1325);
DISPLAY 0.872340 (-2875 -1325);
PAINT AQUA (-2875 -1325);
DISPLAY INVISIBLE (-2875 -1325);
FORCEPROP 1 LAST COMMENT_BODY TRUE
J 0
(-3075 -1300);
DISPLAY 0.872340 (-3075 -1300);
PAINT GREEN (-3075 -1300);
DISPLAY INVISIBLE (-3075 -1300);
FORCEPROP 2 LAST PATH I2
J 0
(-3450 -1150);
DISPLAY 0.680851 (-3450 -1150);
DISPLAY INVISIBLE (-3450 -1150);
FORCEADD OFFPAGE..1
(-3200 500);
FORCEPROP 2 LAST $XR0 276 
J 0
(-3452 500);
DISPLAY 0.638298 (-3452 500);
PAINT MONO (-3452 500);
FORCEPROP 2 LAST CDS_LIB standard
J 0
(-3200 500);
DISPLAY INVISIBLE (-3200 500);
FORCEPROP 1 LAST OFFPAGE TRUE
J 0
(-2875 375);
DISPLAY 0.872340 (-2875 375);
PAINT AQUA (-2875 375);
DISPLAY INVISIBLE (-2875 375);
FORCEPROP 1 LAST COMMENT_BODY TRUE
J 0
(-3075 400);
DISPLAY 0.872340 (-3075 400);
PAINT GREEN (-3075 400);
DISPLAY INVISIBLE (-3075 400);
FORCEPROP 2 LAST PATH I20
J 0
(-3450 550);
DISPLAY 0.680851 (-3450 550);
DISPLAY INVISIBLE (-3450 550);
FORCEADD OFFPAGE..1
(-3200 550);
FORCEPROP 2 LAST $XR0 276 
J 0
(-3452 550);
DISPLAY 0.638298 (-3452 550);
PAINT MONO (-3452 550);
FORCEPROP 2 LAST CDS_LIB standard
J 0
(-3200 550);
DISPLAY INVISIBLE (-3200 550);
FORCEPROP 1 LAST OFFPAGE TRUE
J 0
(-2875 425);
DISPLAY 0.872340 (-2875 425);
PAINT AQUA (-2875 425);
DISPLAY INVISIBLE (-2875 425);
FORCEPROP 1 LAST COMMENT_BODY TRUE
J 0
(-3075 450);
DISPLAY 0.872340 (-3075 450);
PAINT GREEN (-3075 450);
DISPLAY INVISIBLE (-3075 450);
FORCEPROP 2 LAST PATH I21
J 0
(-3450 600);
DISPLAY 0.680851 (-3450 600);
DISPLAY INVISIBLE (-3450 600);
FORCEADD OFFPAGE..5
(-3200 650);
FORCEPROP 2 LAST $XR0 286 
J 0
(-3455 650);
DISPLAY 0.638298 (-3455 650);
PAINT MONO (-3455 650);
FORCEPROP 2 LAST CDS_LIB standard
J 0
(-3200 650);
DISPLAY INVISIBLE (-3200 650);
FORCEPROP 1 LAST OFFPAGE TRUE
J 0
(-2875 525);
DISPLAY 0.872340 (-2875 525);
PAINT AQUA (-2875 525);
DISPLAY INVISIBLE (-2875 525);
FORCEPROP 1 LAST COMMENT_BODY TRUE
J 0
(-3100 575);
DISPLAY 1.170213 (-3100 575);
PAINT GREEN (-3100 575);
DISPLAY INVISIBLE (-3100 575);
FORCEPROP 2 LAST PATH I22
J 0
(-3475 700);
DISPLAY 0.680851 (-3475 700);
DISPLAY INVISIBLE (-3475 700);
FORCEADD OFFPAGE..2
R 2
(-3200 700);
FORCEPROP 2 LAST $XR0 286 
J 0
(-3455 700);
DISPLAY 0.638298 (-3455 700);
PAINT MONO (-3455 700);
FORCEPROP 2 LAST CDS_LIB standard
J 0
(-3200 700);
DISPLAY INVISIBLE (-3200 700);
FORCEPROP 1 LAST OFFPAGE TRUE
J 2
(-3525 575);
DISPLAY 0.872340 (-3525 575);
PAINT AQUA (-3525 575);
DISPLAY INVISIBLE (-3525 575);
FORCEPROP 1 LAST COMMENT_BODY TRUE
J 2
(-3155 605);
DISPLAY 0.872340 (-3155 605);
PAINT GREEN (-3155 605);
DISPLAY INVISIBLE (-3155 605);
FORCEPROP 2 LAST PATH I23
J 0
(-3475 750);
DISPLAY 0.680851 (-3475 750);
DISPLAY INVISIBLE (-3475 750);
FORCEADD OFFPAGE..5
(-3200 800);
FORCEPROP 2 LAST $XR0 275 
J 0
(-3455 800);
DISPLAY 0.638298 (-3455 800);
PAINT MONO (-3455 800);
FORCEPROP 2 LAST CDS_LIB standard
J 0
(-3200 800);
DISPLAY INVISIBLE (-3200 800);
FORCEPROP 1 LAST OFFPAGE TRUE
J 0
(-2875 675);
DISPLAY 0.872340 (-2875 675);
PAINT AQUA (-2875 675);
DISPLAY INVISIBLE (-2875 675);
FORCEPROP 1 LAST COMMENT_BODY TRUE
J 0
(-3100 725);
DISPLAY 1.170213 (-3100 725);
PAINT GREEN (-3100 725);
DISPLAY INVISIBLE (-3100 725);
FORCEPROP 2 LAST PATH I24
J 0
(-3475 850);
DISPLAY 0.680851 (-3475 850);
DISPLAY INVISIBLE (-3475 850);
FORCEADD OFFPAGE..2
R 2
(-3200 850);
FORCEPROP 2 LAST $XR0 275 
J 0
(-3455 850);
DISPLAY 0.638298 (-3455 850);
PAINT MONO (-3455 850);
FORCEPROP 2 LAST CDS_LIB standard
J 0
(-3200 850);
DISPLAY INVISIBLE (-3200 850);
FORCEPROP 1 LAST OFFPAGE TRUE
J 2
(-3525 725);
DISPLAY 0.872340 (-3525 725);
PAINT AQUA (-3525 725);
DISPLAY INVISIBLE (-3525 725);
FORCEPROP 1 LAST COMMENT_BODY TRUE
J 2
(-3155 755);
DISPLAY 0.872340 (-3155 755);
PAINT GREEN (-3155 755);
DISPLAY INVISIBLE (-3155 755);
FORCEPROP 2 LAST PATH I25
J 0
(-3475 900);
DISPLAY 0.680851 (-3475 900);
DISPLAY INVISIBLE (-3475 900);
FORCEADD OFFPAGE..2
R 2
(-3200 950);
FORCEPROP 2 LAST $XR0 125 
J 0
(-3455 950);
DISPLAY 0.638298 (-3455 950);
PAINT MONO (-3455 950);
FORCEPROP 2 LAST CDS_LIB standard
J 0
(-3200 950);
DISPLAY INVISIBLE (-3200 950);
FORCEPROP 1 LAST OFFPAGE TRUE
J 2
(-3525 825);
DISPLAY 0.872340 (-3525 825);
PAINT AQUA (-3525 825);
DISPLAY INVISIBLE (-3525 825);
FORCEPROP 1 LAST COMMENT_BODY TRUE
J 2
(-3155 855);
DISPLAY 0.872340 (-3155 855);
PAINT GREEN (-3155 855);
DISPLAY INVISIBLE (-3155 855);
FORCEPROP 2 LAST PATH I26
J 0
(-3475 1000);
DISPLAY 0.680851 (-3475 1000);
DISPLAY INVISIBLE (-3475 1000);
FORCEADD OFFPAGE..1
(-3200 1100);
FORCEPROP 2 LAST $XR0 124 
J 0
(-3452 1100);
DISPLAY 0.638298 (-3452 1100);
PAINT MONO (-3452 1100);
FORCEPROP 2 LAST CDS_LIB standard
J 0
(-3200 1100);
DISPLAY INVISIBLE (-3200 1100);
FORCEPROP 1 LAST OFFPAGE TRUE
J 0
(-2875 975);
DISPLAY 0.872340 (-2875 975);
PAINT AQUA (-2875 975);
DISPLAY INVISIBLE (-2875 975);
FORCEPROP 1 LAST COMMENT_BODY TRUE
J 0
(-3075 1000);
DISPLAY 0.872340 (-3075 1000);
PAINT GREEN (-3075 1000);
DISPLAY INVISIBLE (-3075 1000);
FORCEPROP 2 LAST PATH I27
J 0
(-3450 1150);
DISPLAY 0.680851 (-3450 1150);
DISPLAY INVISIBLE (-3450 1150);
FORCEADD OFFPAGE..1
(-3200 1250);
FORCEPROP 2 LAST $XR0 287 
J 0
(-3452 1250);
DISPLAY 0.638298 (-3452 1250);
PAINT MONO (-3452 1250);
FORCEPROP 2 LAST CDS_LIB standard
J 0
(-3200 1250);
DISPLAY INVISIBLE (-3200 1250);
FORCEPROP 1 LAST OFFPAGE TRUE
J 0
(-2875 1125);
DISPLAY 0.872340 (-2875 1125);
PAINT AQUA (-2875 1125);
DISPLAY INVISIBLE (-2875 1125);
FORCEPROP 1 LAST COMMENT_BODY TRUE
J 0
(-3075 1150);
DISPLAY 0.872340 (-3075 1150);
PAINT GREEN (-3075 1150);
DISPLAY INVISIBLE (-3075 1150);
FORCEPROP 2 LAST PATH I28
J 0
(-3450 1300);
DISPLAY 0.680851 (-3450 1300);
DISPLAY INVISIBLE (-3450 1300);
FORCEADD OFFPAGE..1
(-3200 1200);
FORCEPROP 2 LAST $XR0 287 
J 0
(-3452 1200);
DISPLAY 0.638298 (-3452 1200);
PAINT MONO (-3452 1200);
FORCEPROP 2 LAST CDS_LIB standard
J 0
(-3200 1200);
DISPLAY INVISIBLE (-3200 1200);
FORCEPROP 1 LAST OFFPAGE TRUE
J 0
(-2875 1075);
DISPLAY 0.872340 (-2875 1075);
PAINT AQUA (-2875 1075);
DISPLAY INVISIBLE (-2875 1075);
FORCEPROP 1 LAST COMMENT_BODY TRUE
J 0
(-3075 1100);
DISPLAY 0.872340 (-3075 1100);
PAINT GREEN (-3075 1100);
DISPLAY INVISIBLE (-3075 1100);
FORCEPROP 2 LAST PATH I29
J 0
(-3450 1250);
DISPLAY 0.680851 (-3450 1250);
DISPLAY INVISIBLE (-3450 1250);
FORCEADD OFFPAGE..1
(-3200 -1050);
FORCEPROP 2 LAST $XR0 276 
J 0
(-3452 -1050);
DISPLAY 0.638298 (-3452 -1050);
PAINT MONO (-3452 -1050);
FORCEPROP 2 LAST CDS_LIB standard
J 0
(-3200 -1050);
DISPLAY INVISIBLE (-3200 -1050);
FORCEPROP 1 LAST OFFPAGE TRUE
J 0
(-2875 -1175);
DISPLAY 0.872340 (-2875 -1175);
PAINT AQUA (-2875 -1175);
DISPLAY INVISIBLE (-2875 -1175);
FORCEPROP 1 LAST COMMENT_BODY TRUE
J 0
(-3075 -1150);
DISPLAY 0.872340 (-3075 -1150);
PAINT GREEN (-3075 -1150);
DISPLAY INVISIBLE (-3075 -1150);
FORCEPROP 2 LAST PATH I3
J 0
(-3450 -1000);
DISPLAY 0.680851 (-3450 -1000);
DISPLAY INVISIBLE (-3450 -1000);
FORCEADD OFFPAGE..1
(-3200 1350);
FORCEPROP 2 LAST $XR0 276 
J 0
(-3452 1350);
DISPLAY 0.638298 (-3452 1350);
PAINT MONO (-3452 1350);
FORCEPROP 2 LAST CDS_LIB standard
J 0
(-3200 1350);
DISPLAY INVISIBLE (-3200 1350);
FORCEPROP 1 LAST OFFPAGE TRUE
J 0
(-2875 1225);
DISPLAY 0.872340 (-2875 1225);
PAINT AQUA (-2875 1225);
DISPLAY INVISIBLE (-2875 1225);
FORCEPROP 1 LAST COMMENT_BODY TRUE
J 0
(-3075 1250);
DISPLAY 0.872340 (-3075 1250);
PAINT GREEN (-3075 1250);
DISPLAY INVISIBLE (-3075 1250);
FORCEPROP 2 LAST PATH I30
J 0
(-3450 1375);
DISPLAY 0.680851 (-3450 1375);
DISPLAY INVISIBLE (-3450 1375);
FORCEADD OFFPAGE..1
(-3200 1400);
FORCEPROP 2 LAST $XR0 276 
J 0
(-3452 1400);
DISPLAY 0.638298 (-3452 1400);
PAINT MONO (-3452 1400);
FORCEPROP 2 LAST CDS_LIB standard
J 0
(-3200 1400);
DISPLAY INVISIBLE (-3200 1400);
FORCEPROP 1 LAST OFFPAGE TRUE
J 0
(-2875 1275);
DISPLAY 0.872340 (-2875 1275);
PAINT AQUA (-2875 1275);
DISPLAY INVISIBLE (-2875 1275);
FORCEPROP 1 LAST COMMENT_BODY TRUE
J 0
(-3075 1300);
DISPLAY 0.872340 (-3075 1300);
PAINT GREEN (-3075 1300);
DISPLAY INVISIBLE (-3075 1300);
FORCEPROP 2 LAST PATH I31
J 0
(-3450 1450);
DISPLAY 0.680851 (-3450 1450);
DISPLAY INVISIBLE (-3450 1450);
FORCEADD OFFPAGE..5
(-3200 1500);
FORCEPROP 2 LAST $XR0 286 
J 0
(-3455 1500);
DISPLAY 0.638298 (-3455 1500);
PAINT MONO (-3455 1500);
FORCEPROP 2 LAST CDS_LIB standard
J 0
(-3200 1500);
DISPLAY INVISIBLE (-3200 1500);
FORCEPROP 1 LAST OFFPAGE TRUE
J 0
(-2875 1375);
DISPLAY 0.872340 (-2875 1375);
PAINT AQUA (-2875 1375);
DISPLAY INVISIBLE (-2875 1375);
FORCEPROP 1 LAST COMMENT_BODY TRUE
J 0
(-3100 1425);
DISPLAY 1.170213 (-3100 1425);
PAINT GREEN (-3100 1425);
DISPLAY INVISIBLE (-3100 1425);
FORCEPROP 2 LAST PATH I32
J 0
(-3475 1550);
DISPLAY 0.680851 (-3475 1550);
DISPLAY INVISIBLE (-3475 1550);
FORCEADD OFFPAGE..2
R 2
(-3200 1550);
FORCEPROP 2 LAST $XR0 286 
J 0
(-3455 1550);
DISPLAY 0.638298 (-3455 1550);
PAINT MONO (-3455 1550);
FORCEPROP 2 LAST CDS_LIB standard
J 0
(-3200 1550);
DISPLAY INVISIBLE (-3200 1550);
FORCEPROP 1 LAST OFFPAGE TRUE
J 2
(-3525 1425);
DISPLAY 0.872340 (-3525 1425);
PAINT AQUA (-3525 1425);
DISPLAY INVISIBLE (-3525 1425);
FORCEPROP 1 LAST COMMENT_BODY TRUE
J 2
(-3155 1455);
DISPLAY 0.872340 (-3155 1455);
PAINT GREEN (-3155 1455);
DISPLAY INVISIBLE (-3155 1455);
FORCEPROP 2 LAST PATH I33
J 0
(-3475 1600);
DISPLAY 0.680851 (-3475 1600);
DISPLAY INVISIBLE (-3475 1600);
FORCEADD OFFPAGE..2
R 2
(-3200 1700);
FORCEPROP 2 LAST $XR0 275 
J 0
(-3455 1700);
DISPLAY 0.638298 (-3455 1700);
PAINT MONO (-3455 1700);
FORCEPROP 2 LAST CDS_LIB standard
J 0
(-3200 1700);
DISPLAY INVISIBLE (-3200 1700);
FORCEPROP 1 LAST OFFPAGE TRUE
J 2
(-3525 1575);
DISPLAY 0.872340 (-3525 1575);
PAINT AQUA (-3525 1575);
DISPLAY INVISIBLE (-3525 1575);
FORCEPROP 1 LAST COMMENT_BODY TRUE
J 2
(-3155 1605);
DISPLAY 0.872340 (-3155 1605);
PAINT GREEN (-3155 1605);
DISPLAY INVISIBLE (-3155 1605);
FORCEPROP 2 LAST PATH I34
J 0
(-3475 1750);
DISPLAY 0.680851 (-3475 1750);
DISPLAY INVISIBLE (-3475 1750);
FORCEADD OFFPAGE..5
(-3200 1650);
FORCEPROP 2 LAST $XR0 275 
J 0
(-3455 1650);
DISPLAY 0.638298 (-3455 1650);
PAINT MONO (-3455 1650);
FORCEPROP 2 LAST CDS_LIB standard
J 0
(-3200 1650);
DISPLAY INVISIBLE (-3200 1650);
FORCEPROP 1 LAST OFFPAGE TRUE
J 0
(-2875 1525);
DISPLAY 0.872340 (-2875 1525);
PAINT AQUA (-2875 1525);
DISPLAY INVISIBLE (-2875 1525);
FORCEPROP 1 LAST COMMENT_BODY TRUE
J 0
(-3100 1575);
DISPLAY 1.170213 (-3100 1575);
PAINT GREEN (-3100 1575);
DISPLAY INVISIBLE (-3100 1575);
FORCEPROP 2 LAST PATH I35
J 0
(-3475 1700);
DISPLAY 0.680851 (-3475 1700);
DISPLAY INVISIBLE (-3475 1700);
FORCEADD OFFPAGE..1
(1300 -1250);
FORCEPROP 2 LAST $XR0 287 
J 0
(1048 -1250);
DISPLAY 0.638298 (1048 -1250);
PAINT MONO (1048 -1250);
FORCEPROP 2 LAST CDS_LIB standard
J 0
(1300 -1250);
DISPLAY INVISIBLE (1300 -1250);
FORCEPROP 1 LAST OFFPAGE TRUE
J 0
(1625 -1375);
DISPLAY 0.872340 (1625 -1375);
PAINT AQUA (1625 -1375);
DISPLAY INVISIBLE (1625 -1375);
FORCEPROP 1 LAST COMMENT_BODY TRUE
J 0
(1425 -1350);
DISPLAY 0.872340 (1425 -1350);
PAINT GREEN (1425 -1350);
DISPLAY INVISIBLE (1425 -1350);
FORCEPROP 2 LAST PATH I36
J 0
(1050 -1200);
DISPLAY 0.680851 (1050 -1200);
DISPLAY INVISIBLE (1050 -1200);
FORCEADD OFFPAGE..1
(1300 -1200);
FORCEPROP 2 LAST $XR0 287 
J 0
(1048 -1200);
DISPLAY 0.638298 (1048 -1200);
PAINT MONO (1048 -1200);
FORCEPROP 2 LAST CDS_LIB standard
J 0
(1300 -1200);
DISPLAY INVISIBLE (1300 -1200);
FORCEPROP 1 LAST OFFPAGE TRUE
J 0
(1625 -1325);
DISPLAY 0.872340 (1625 -1325);
PAINT AQUA (1625 -1325);
DISPLAY INVISIBLE (1625 -1325);
FORCEPROP 1 LAST COMMENT_BODY TRUE
J 0
(1425 -1300);
DISPLAY 0.872340 (1425 -1300);
PAINT GREEN (1425 -1300);
DISPLAY INVISIBLE (1425 -1300);
FORCEPROP 2 LAST PATH I37
J 0
(1050 -1150);
DISPLAY 0.680851 (1050 -1150);
DISPLAY INVISIBLE (1050 -1150);
FORCEADD OFFPAGE..1
(1300 -1100);
FORCEPROP 2 LAST $XR0 276 
J 0
(1048 -1100);
DISPLAY 0.638298 (1048 -1100);
PAINT MONO (1048 -1100);
FORCEPROP 2 LAST CDS_LIB standard
J 0
(1300 -1100);
DISPLAY INVISIBLE (1300 -1100);
FORCEPROP 1 LAST OFFPAGE TRUE
J 0
(1625 -1225);
DISPLAY 0.872340 (1625 -1225);
PAINT AQUA (1625 -1225);
DISPLAY INVISIBLE (1625 -1225);
FORCEPROP 1 LAST COMMENT_BODY TRUE
J 0
(1425 -1200);
DISPLAY 0.872340 (1425 -1200);
PAINT GREEN (1425 -1200);
DISPLAY INVISIBLE (1425 -1200);
FORCEPROP 2 LAST PATH I38
J 0
(1050 -1050);
DISPLAY 0.680851 (1050 -1050);
DISPLAY INVISIBLE (1050 -1050);
FORCEADD OFFPAGE..1
(1300 -1050);
FORCEPROP 2 LAST $XR0 276 
J 0
(1048 -1050);
DISPLAY 0.638298 (1048 -1050);
PAINT MONO (1048 -1050);
FORCEPROP 2 LAST CDS_LIB standard
J 0
(1300 -1050);
DISPLAY INVISIBLE (1300 -1050);
FORCEPROP 1 LAST OFFPAGE TRUE
J 0
(1625 -1175);
DISPLAY 0.872340 (1625 -1175);
PAINT AQUA (1625 -1175);
DISPLAY INVISIBLE (1625 -1175);
FORCEPROP 1 LAST COMMENT_BODY TRUE
J 0
(1425 -1150);
DISPLAY 0.872340 (1425 -1150);
PAINT GREEN (1425 -1150);
DISPLAY INVISIBLE (1425 -1150);
FORCEPROP 2 LAST PATH I39
J 0
(1050 -1000);
DISPLAY 0.680851 (1050 -1000);
DISPLAY INVISIBLE (1050 -1000);
FORCEADD OFFPAGE..5
(-3200 -950);
FORCEPROP 2 LAST $XR0 286 
J 0
(-3455 -950);
DISPLAY 0.638298 (-3455 -950);
PAINT MONO (-3455 -950);
FORCEPROP 2 LAST CDS_LIB standard
J 0
(-3200 -950);
DISPLAY INVISIBLE (-3200 -950);
FORCEPROP 1 LAST OFFPAGE TRUE
J 0
(-2875 -1075);
DISPLAY 0.872340 (-2875 -1075);
PAINT AQUA (-2875 -1075);
DISPLAY INVISIBLE (-2875 -1075);
FORCEPROP 1 LAST COMMENT_BODY TRUE
J 0
(-3100 -1025);
DISPLAY 1.170213 (-3100 -1025);
PAINT GREEN (-3100 -1025);
DISPLAY INVISIBLE (-3100 -1025);
FORCEPROP 2 LAST PATH I4
J 0
(-3475 -900);
DISPLAY 0.680851 (-3475 -900);
DISPLAY INVISIBLE (-3475 -900);
FORCEADD OFFPAGE..5
(1300 -950);
FORCEPROP 2 LAST $XR0 286 
J 0
(1045 -950);
DISPLAY 0.638298 (1045 -950);
PAINT MONO (1045 -950);
FORCEPROP 2 LAST CDS_LIB standard
J 0
(1300 -950);
DISPLAY INVISIBLE (1300 -950);
FORCEPROP 1 LAST OFFPAGE TRUE
J 0
(1625 -1075);
DISPLAY 0.872340 (1625 -1075);
PAINT AQUA (1625 -1075);
DISPLAY INVISIBLE (1625 -1075);
FORCEPROP 1 LAST COMMENT_BODY TRUE
J 0
(1400 -1025);
DISPLAY 1.170213 (1400 -1025);
PAINT GREEN (1400 -1025);
DISPLAY INVISIBLE (1400 -1025);
FORCEPROP 2 LAST PATH I40
J 0
(1025 -900);
DISPLAY 0.680851 (1025 -900);
DISPLAY INVISIBLE (1025 -900);
FORCEADD OFFPAGE..2
R 2
(1300 -900);
FORCEPROP 2 LAST $XR0 286 
J 0
(1045 -900);
DISPLAY 0.638298 (1045 -900);
PAINT MONO (1045 -900);
FORCEPROP 2 LAST CDS_LIB standard
J 0
(1300 -900);
DISPLAY INVISIBLE (1300 -900);
FORCEPROP 1 LAST OFFPAGE TRUE
J 2
(975 -1025);
DISPLAY 0.872340 (975 -1025);
PAINT AQUA (975 -1025);
DISPLAY INVISIBLE (975 -1025);
FORCEPROP 1 LAST COMMENT_BODY TRUE
J 2
(1345 -995);
DISPLAY 0.872340 (1345 -995);
PAINT GREEN (1345 -995);
DISPLAY INVISIBLE (1345 -995);
FORCEPROP 2 LAST PATH I41
J 0
(1025 -850);
DISPLAY 0.680851 (1025 -850);
DISPLAY INVISIBLE (1025 -850);
FORCEADD OFFPAGE..5
(1300 -800);
FORCEPROP 2 LAST $XR0 275 
J 0
(1045 -800);
DISPLAY 0.638298 (1045 -800);
PAINT MONO (1045 -800);
FORCEPROP 2 LAST CDS_LIB standard
J 0
(1300 -800);
DISPLAY INVISIBLE (1300 -800);
FORCEPROP 1 LAST OFFPAGE TRUE
J 0
(1625 -925);
DISPLAY 0.872340 (1625 -925);
PAINT AQUA (1625 -925);
DISPLAY INVISIBLE (1625 -925);
FORCEPROP 1 LAST COMMENT_BODY TRUE
J 0
(1400 -875);
DISPLAY 1.170213 (1400 -875);
PAINT GREEN (1400 -875);
DISPLAY INVISIBLE (1400 -875);
FORCEPROP 2 LAST PATH I42
J 0
(1025 -750);
DISPLAY 0.680851 (1025 -750);
DISPLAY INVISIBLE (1025 -750);
FORCEADD OFFPAGE..2
R 2
(1300 -750);
FORCEPROP 2 LAST $XR0 275 
J 0
(1045 -750);
DISPLAY 0.638298 (1045 -750);
PAINT MONO (1045 -750);
FORCEPROP 2 LAST CDS_LIB standard
J 0
(1300 -750);
DISPLAY INVISIBLE (1300 -750);
FORCEPROP 1 LAST OFFPAGE TRUE
J 2
(975 -875);
DISPLAY 0.872340 (975 -875);
PAINT AQUA (975 -875);
DISPLAY INVISIBLE (975 -875);
FORCEPROP 1 LAST COMMENT_BODY TRUE
J 2
(1345 -845);
DISPLAY 0.872340 (1345 -845);
PAINT GREEN (1345 -845);
DISPLAY INVISIBLE (1345 -845);
FORCEPROP 2 LAST PATH I43
J 0
(1025 -700);
DISPLAY 0.680851 (1025 -700);
DISPLAY INVISIBLE (1025 -700);
FORCEADD OFFPAGE..1
(1300 -400);
FORCEPROP 2 LAST $XR0 287 
J 0
(1048 -400);
DISPLAY 0.638298 (1048 -400);
PAINT MONO (1048 -400);
FORCEPROP 2 LAST CDS_LIB standard
J 0
(1300 -400);
DISPLAY INVISIBLE (1300 -400);
FORCEPROP 1 LAST OFFPAGE TRUE
J 0
(1625 -525);
DISPLAY 0.872340 (1625 -525);
PAINT AQUA (1625 -525);
DISPLAY INVISIBLE (1625 -525);
FORCEPROP 1 LAST COMMENT_BODY TRUE
J 0
(1425 -500);
DISPLAY 0.872340 (1425 -500);
PAINT GREEN (1425 -500);
DISPLAY INVISIBLE (1425 -500);
FORCEPROP 2 LAST PATH I44
J 0
(1050 -350);
DISPLAY 0.680851 (1050 -350);
DISPLAY INVISIBLE (1050 -350);
FORCEADD OFFPAGE..1
(1300 -350);
FORCEPROP 2 LAST $XR0 287 
J 0
(1048 -350);
DISPLAY 0.638298 (1048 -350);
PAINT MONO (1048 -350);
FORCEPROP 2 LAST CDS_LIB standard
J 0
(1300 -350);
DISPLAY INVISIBLE (1300 -350);
FORCEPROP 1 LAST OFFPAGE TRUE
J 0
(1625 -475);
DISPLAY 0.872340 (1625 -475);
PAINT AQUA (1625 -475);
DISPLAY INVISIBLE (1625 -475);
FORCEPROP 1 LAST COMMENT_BODY TRUE
J 0
(1425 -450);
DISPLAY 0.872340 (1425 -450);
PAINT GREEN (1425 -450);
DISPLAY INVISIBLE (1425 -450);
FORCEPROP 2 LAST PATH I45
J 0
(1050 -300);
DISPLAY 0.680851 (1050 -300);
DISPLAY INVISIBLE (1050 -300);
FORCEADD OFFPAGE..1
(1300 -250);
FORCEPROP 2 LAST $XR0 276 
J 0
(1048 -250);
DISPLAY 0.638298 (1048 -250);
PAINT MONO (1048 -250);
FORCEPROP 2 LAST CDS_LIB standard
J 0
(1300 -250);
DISPLAY INVISIBLE (1300 -250);
FORCEPROP 1 LAST OFFPAGE TRUE
J 0
(1625 -375);
DISPLAY 0.872340 (1625 -375);
PAINT AQUA (1625 -375);
DISPLAY INVISIBLE (1625 -375);
FORCEPROP 1 LAST COMMENT_BODY TRUE
J 0
(1425 -350);
DISPLAY 0.872340 (1425 -350);
PAINT GREEN (1425 -350);
DISPLAY INVISIBLE (1425 -350);
FORCEPROP 2 LAST PATH I46
J 0
(1025 -200);
DISPLAY 0.680851 (1025 -200);
DISPLAY INVISIBLE (1025 -200);
FORCEADD OFFPAGE..1
(1300 -200);
FORCEPROP 2 LAST $XR0 276 
J 0
(1048 -200);
DISPLAY 0.638298 (1048 -200);
PAINT MONO (1048 -200);
FORCEPROP 2 LAST CDS_LIB standard
J 0
(1300 -200);
DISPLAY INVISIBLE (1300 -200);
FORCEPROP 1 LAST OFFPAGE TRUE
J 0
(1625 -325);
DISPLAY 0.872340 (1625 -325);
PAINT AQUA (1625 -325);
DISPLAY INVISIBLE (1625 -325);
FORCEPROP 1 LAST COMMENT_BODY TRUE
J 0
(1425 -300);
DISPLAY 0.872340 (1425 -300);
PAINT GREEN (1425 -300);
DISPLAY INVISIBLE (1425 -300);
FORCEPROP 2 LAST PATH I47
J 0
(1025 -150);
DISPLAY 0.680851 (1025 -150);
DISPLAY INVISIBLE (1025 -150);
FORCEADD UNIVERSAL_GND..1
(2350 -1700);
FORCEPROP 3 LASTPIN (2350 -1650) SIG_NAME GND\g
J 0
(2360 -1640);
DISPLAY 0.659574 (2360 -1640);
PAINT MONO (2360 -1640);
DISPLAY INVISIBLE (2360 -1640);
FORCEPROP 2 LAST CDS_LIB pure_quanta_power
J 0
(2350 -1700);
DISPLAY INVISIBLE (2350 -1700);
FORCEPROP 1 LAST HDL_POWER GND
J 1
(2375 -1775);
DISPLAY 0.872340 (2375 -1775);
PAINT GREEN (2375 -1775);
DISPLAY INVISIBLE (2375 -1775);
FORCEPROP 1 LAST PATH I48
J 0
(2425 -1700);
DISPLAY 0.872340 (2425 -1700);
PAINT AQUA (2425 -1700);
DISPLAY INVISIBLE (2425 -1700);
FORCEADD CONN112_10137002101LF..2
(3500 250);
FORCEPROP 1 LAST LOCATION J107
J 0
(2750 2075);
DISPLAY 0.723404 (2750 2075);
PAINT GREEN (2750 2075);
FORCEPROP 0 LAST $SEC 2
J 0
(2750 2200);
DISPLAY 0.680851 (2750 2200);
PAINT MONO (2750 2200);
DISPLAY INVISIBLE (2750 2200);
FORCEPROP 0 LAST CDS_SEC 2
J 0
(2750 2200);
DISPLAY 1.021277 (2750 2200);
DISPLAY INVISIBLE (2750 2200);
FORCEPROP 0 LASTPIN (2575 -650) $PN A1
J 2
(2565 -640);
DISPLAY 0.680851 (2565 -640);
PAINT MONO (2565 -640);
FORCEPROP 0 LASTPIN (2575 150) $PN A2
J 2
(2565 160);
DISPLAY 0.680851 (2565 160);
PAINT MONO (2565 160);
FORCEPROP 0 LASTPIN (2575 950) $PN A3
J 2
(2565 960);
DISPLAY 0.680851 (2565 960);
PAINT MONO (2565 960);
FORCEPROP 0 LASTPIN (2575 1750) $PN A4
J 2
(2565 1760);
DISPLAY 0.680851 (2565 1760);
PAINT MONO (2565 1760);
FORCEPROP 0 LASTPIN (2575 -700) $PN B1
J 2
(2565 -690);
DISPLAY 0.680851 (2565 -690);
PAINT MONO (2565 -690);
FORCEPROP 0 LASTPIN (2575 100) $PN B2
J 2
(2565 110);
DISPLAY 0.680851 (2565 110);
PAINT MONO (2565 110);
FORCEPROP 0 LASTPIN (2575 900) $PN B3
J 2
(2565 910);
DISPLAY 0.680851 (2565 910);
PAINT MONO (2565 910);
FORCEPROP 0 LASTPIN (2575 1700) $PN B4
J 2
(2565 1710);
DISPLAY 0.680851 (2565 1710);
PAINT MONO (2565 1710);
FORCEPROP 0 LASTPIN (2575 -750) $PN C1
J 2
(2565 -740);
DISPLAY 0.680851 (2565 -740);
PAINT MONO (2565 -740);
FORCEPROP 0 LASTPIN (2575 50) $PN C2
J 2
(2565 60);
DISPLAY 0.680851 (2565 60);
PAINT MONO (2565 60);
FORCEPROP 0 LASTPIN (2575 850) $PN C3
J 2
(2565 860);
DISPLAY 0.680851 (2565 860);
PAINT MONO (2565 860);
FORCEPROP 0 LASTPIN (2575 1650) $PN C4
J 2
(2565 1660);
DISPLAY 0.680851 (2565 1660);
PAINT MONO (2565 1660);
FORCEPROP 0 LASTPIN (2575 -800) $PN D1
J 2
(2565 -790);
DISPLAY 0.680851 (2565 -790);
PAINT MONO (2565 -790);
FORCEPROP 0 LASTPIN (2575 0) $PN D2
J 2
(2565 10);
DISPLAY 0.680851 (2565 10);
PAINT MONO (2565 10);
FORCEPROP 0 LASTPIN (2575 800) $PN D3
J 2
(2565 810);
DISPLAY 0.680851 (2565 810);
PAINT MONO (2565 810);
FORCEPROP 0 LASTPIN (2575 1600) $PN D4
J 2
(2565 1610);
DISPLAY 0.680851 (2565 1610);
PAINT MONO (2565 1610);
FORCEPROP 0 LASTPIN (2575 -850) $PN E1
J 2
(2565 -840);
DISPLAY 0.680851 (2565 -840);
PAINT MONO (2565 -840);
FORCEPROP 0 LASTPIN (2575 -50) $PN E2
J 2
(2565 -40);
DISPLAY 0.680851 (2565 -40);
PAINT MONO (2565 -40);
FORCEPROP 0 LASTPIN (2575 750) $PN E3
J 2
(2565 760);
DISPLAY 0.680851 (2565 760);
PAINT MONO (2565 760);
FORCEPROP 0 LASTPIN (2575 1550) $PN E4
J 2
(2565 1560);
DISPLAY 0.680851 (2565 1560);
PAINT MONO (2565 1560);
FORCEPROP 0 LASTPIN (2575 -900) $PN F1
J 2
(2565 -890);
DISPLAY 0.680851 (2565 -890);
PAINT MONO (2565 -890);
FORCEPROP 0 LASTPIN (2575 -100) $PN F2
J 2
(2565 -90);
DISPLAY 0.680851 (2565 -90);
PAINT MONO (2565 -90);
FORCEPROP 0 LASTPIN (2575 700) $PN F3
J 2
(2565 710);
DISPLAY 0.680851 (2565 710);
PAINT MONO (2565 710);
FORCEPROP 0 LASTPIN (2575 1500) $PN F4
J 2
(2565 1510);
DISPLAY 0.680851 (2565 1510);
PAINT MONO (2565 1510);
FORCEPROP 0 LASTPIN (2575 -950) $PN G1
J 2
(2565 -940);
DISPLAY 0.680851 (2565 -940);
PAINT MONO (2565 -940);
FORCEPROP 0 LASTPIN (2575 -150) $PN G2
J 2
(2565 -140);
DISPLAY 0.680851 (2565 -140);
PAINT MONO (2565 -140);
FORCEPROP 0 LASTPIN (2575 650) $PN G3
J 2
(2565 660);
DISPLAY 0.680851 (2565 660);
PAINT MONO (2565 660);
FORCEPROP 0 LASTPIN (2575 1450) $PN G4
J 2
(2565 1460);
DISPLAY 0.680851 (2565 1460);
PAINT MONO (2565 1460);
FORCEPROP 0 LASTPIN (2575 -1000) $PN H1
J 2
(2565 -990);
DISPLAY 0.680851 (2565 -990);
PAINT MONO (2565 -990);
FORCEPROP 0 LASTPIN (2575 -200) $PN H2
J 2
(2565 -190);
DISPLAY 0.680851 (2565 -190);
PAINT MONO (2565 -190);
FORCEPROP 0 LASTPIN (2575 600) $PN H3
J 2
(2565 610);
DISPLAY 0.680851 (2565 610);
PAINT MONO (2565 610);
FORCEPROP 0 LASTPIN (2575 1400) $PN H4
J 2
(2565 1410);
DISPLAY 0.680851 (2565 1410);
PAINT MONO (2565 1410);
FORCEPROP 0 LASTPIN (2575 -1050) $PN I1
J 2
(2565 -1040);
DISPLAY 0.680851 (2565 -1040);
PAINT MONO (2565 -1040);
FORCEPROP 0 LASTPIN (2575 -250) $PN I2
J 2
(2565 -240);
DISPLAY 0.680851 (2565 -240);
PAINT MONO (2565 -240);
FORCEPROP 0 LASTPIN (2575 550) $PN I3
J 2
(2565 560);
DISPLAY 0.680851 (2565 560);
PAINT MONO (2565 560);
FORCEPROP 0 LASTPIN (2575 1350) $PN I4
J 2
(2565 1360);
DISPLAY 0.680851 (2565 1360);
PAINT MONO (2565 1360);
FORCEPROP 0 LASTPIN (2575 -1100) $PN J1
J 2
(2565 -1090);
DISPLAY 0.680851 (2565 -1090);
PAINT MONO (2565 -1090);
FORCEPROP 0 LASTPIN (2575 -300) $PN J2
J 2
(2565 -290);
DISPLAY 0.680851 (2565 -290);
PAINT MONO (2565 -290);
FORCEPROP 0 LASTPIN (2575 500) $PN J3
J 2
(2565 510);
DISPLAY 0.680851 (2565 510);
PAINT MONO (2565 510);
FORCEPROP 0 LASTPIN (2575 1300) $PN J4
J 2
(2565 1310);
DISPLAY 0.680851 (2565 1310);
PAINT MONO (2565 1310);
FORCEPROP 0 LASTPIN (2575 -1150) $PN K1
J 2
(2565 -1140);
DISPLAY 0.680851 (2565 -1140);
PAINT MONO (2565 -1140);
FORCEPROP 0 LASTPIN (2575 -350) $PN K2
J 2
(2565 -340);
DISPLAY 0.680851 (2565 -340);
PAINT MONO (2565 -340);
FORCEPROP 0 LASTPIN (2575 450) $PN K3
J 2
(2565 460);
DISPLAY 0.680851 (2565 460);
PAINT MONO (2565 460);
FORCEPROP 0 LASTPIN (2575 1250) $PN K4
J 2
(2565 1260);
DISPLAY 0.680851 (2565 1260);
PAINT MONO (2565 1260);
FORCEPROP 0 LASTPIN (2575 -1200) $PN L1
J 2
(2565 -1190);
DISPLAY 0.680851 (2565 -1190);
PAINT MONO (2565 -1190);
FORCEPROP 0 LASTPIN (2575 -400) $PN L2
J 2
(2565 -390);
DISPLAY 0.680851 (2565 -390);
PAINT MONO (2565 -390);
FORCEPROP 0 LASTPIN (2575 400) $PN L3
J 2
(2565 410);
DISPLAY 0.680851 (2565 410);
PAINT MONO (2565 410);
FORCEPROP 0 LASTPIN (2575 1200) $PN L4
J 2
(2565 1210);
DISPLAY 0.680851 (2565 1210);
PAINT MONO (2565 1210);
FORCEPROP 0 LASTPIN (2575 -1250) $PN M1
J 2
(2565 -1240);
DISPLAY 0.680851 (2565 -1240);
PAINT MONO (2565 -1240);
FORCEPROP 0 LASTPIN (2575 -450) $PN M2
J 2
(2565 -440);
DISPLAY 0.680851 (2565 -440);
PAINT MONO (2565 -440);
FORCEPROP 0 LASTPIN (2575 350) $PN M3
J 2
(2565 360);
DISPLAY 0.680851 (2565 360);
PAINT MONO (2565 360);
FORCEPROP 0 LASTPIN (2575 1150) $PN M4
J 2
(2565 1160);
DISPLAY 0.680851 (2565 1160);
PAINT MONO (2565 1160);
FORCEPROP 0 LASTPIN (2575 -1300) $PN N1
J 2
(2565 -1290);
DISPLAY 0.680851 (2565 -1290);
PAINT MONO (2565 -1290);
FORCEPROP 0 LASTPIN (2575 -500) $PN N2
J 2
(2565 -490);
DISPLAY 0.680851 (2565 -490);
PAINT MONO (2565 -490);
FORCEPROP 0 LASTPIN (2575 300) $PN N3
J 2
(2565 310);
DISPLAY 0.680851 (2565 310);
PAINT MONO (2565 310);
FORCEPROP 0 LASTPIN (2575 1100) $PN N4
J 2
(2565 1110);
DISPLAY 0.680851 (2565 1110);
PAINT MONO (2565 1110);
FORCEPROP 2 LAST PART_TYPE THLF
J 0
(2750 2150);
DISPLAY 1.021277 (2750 2150);
FORCEPROP 1 LAST MATERIAL IO
J 0
(2758 1963);
DISPLAY 0.723404 (2758 1963);
PAINT GREEN (2758 1963);
FORCEPROP 2 LAST CDS_LIB pure_quanta
J 0
(3500 250);
DISPLAY INVISIBLE (3500 250);
FORCEPROP 1 LAST CDS_LMAN_SYM_OUTLINE -775,1650,775,-1650
J 0
(3500 250);
DISPLAY 0.468085 (3500 250);
PAINT GREEN (3500 250);
DISPLAY INVISIBLE (3500 250);
FORCEPROP 0 LAST VALUE CONN112_10137002-101LF
J 0
(2750 2150);
DISPLAY 1.021277 (2750 2150);
DISPLAY INVISIBLE (2750 2150);
FORCEPROP 1 LAST NEEDS_NO_SIZE TRUE
J 0
(3500 250);
DISPLAY 0.723404 (3500 250);
PAINT GREEN (3500 250);
DISPLAY INVISIBLE (3500 250);
FORCEPROP 1 LAST PATH I49
J 0
(3500 250);
DISPLAY 0.723404 (3500 250);
PAINT GREEN (3500 250);
DISPLAY INVISIBLE (3500 250);
FORCEPROP 1 LAST PART_NUMBER DFHSB2FR012
J 0
(2750 2025);
DISPLAY 0.723404 (2750 2025);
PAINT GREEN (2750 2025);
DISPLAY INVISIBLE (2750 2025);
FORCEADD OFFPAGE..1
(-3200 -1100);
FORCEPROP 2 LAST $XR0 276 
J 0
(-3452 -1100);
DISPLAY 0.638298 (-3452 -1100);
PAINT MONO (-3452 -1100);
FORCEPROP 2 LAST CDS_LIB standard
J 0
(-3200 -1100);
DISPLAY INVISIBLE (-3200 -1100);
FORCEPROP 1 LAST OFFPAGE TRUE
J 0
(-2875 -1225);
DISPLAY 0.872340 (-2875 -1225);
PAINT AQUA (-2875 -1225);
DISPLAY INVISIBLE (-2875 -1225);
FORCEPROP 1 LAST COMMENT_BODY TRUE
J 0
(-3075 -1200);
DISPLAY 0.872340 (-3075 -1200);
PAINT GREEN (-3075 -1200);
DISPLAY INVISIBLE (-3075 -1200);
FORCEPROP 2 LAST PATH I5
J 0
(-3450 -1050);
DISPLAY 0.680851 (-3450 -1050);
DISPLAY INVISIBLE (-3450 -1050);
FORCEADD OFFPAGE..2
R 2
(1300 -50);
FORCEPROP 2 LAST $XR0 286 
J 0
(1045 -50);
DISPLAY 0.638298 (1045 -50);
PAINT MONO (1045 -50);
FORCEPROP 2 LAST CDS_LIB standard
J 0
(1300 -50);
DISPLAY INVISIBLE (1300 -50);
FORCEPROP 1 LAST OFFPAGE TRUE
J 2
(975 -175);
DISPLAY 0.872340 (975 -175);
PAINT AQUA (975 -175);
DISPLAY INVISIBLE (975 -175);
FORCEPROP 1 LAST COMMENT_BODY TRUE
J 2
(1345 -145);
DISPLAY 0.872340 (1345 -145);
PAINT GREEN (1345 -145);
DISPLAY INVISIBLE (1345 -145);
FORCEPROP 2 LAST PATH I50
J 0
(1025 0);
DISPLAY 0.680851 (1025 0);
DISPLAY INVISIBLE (1025 0);
FORCEADD OFFPAGE..5
(1300 -100);
FORCEPROP 2 LAST $XR0 286 
J 0
(1045 -100);
DISPLAY 0.638298 (1045 -100);
PAINT MONO (1045 -100);
FORCEPROP 2 LAST CDS_LIB standard
J 0
(1300 -100);
DISPLAY INVISIBLE (1300 -100);
FORCEPROP 1 LAST OFFPAGE TRUE
J 0
(1625 -225);
DISPLAY 0.872340 (1625 -225);
PAINT AQUA (1625 -225);
DISPLAY INVISIBLE (1625 -225);
FORCEPROP 1 LAST COMMENT_BODY TRUE
J 0
(1400 -175);
DISPLAY 1.170213 (1400 -175);
PAINT GREEN (1400 -175);
DISPLAY INVISIBLE (1400 -175);
FORCEPROP 2 LAST PATH I51
J 0
(1025 -50);
DISPLAY 0.680851 (1025 -50);
DISPLAY INVISIBLE (1025 -50);
FORCEADD OFFPAGE..5
(1300 50);
FORCEPROP 2 LAST $XR0 275 
J 0
(1045 50);
DISPLAY 0.638298 (1045 50);
PAINT MONO (1045 50);
FORCEPROP 2 LAST CDS_LIB standard
J 0
(1300 50);
DISPLAY INVISIBLE (1300 50);
FORCEPROP 1 LAST OFFPAGE TRUE
J 0
(1625 -75);
DISPLAY 0.872340 (1625 -75);
PAINT AQUA (1625 -75);
DISPLAY INVISIBLE (1625 -75);
FORCEPROP 1 LAST COMMENT_BODY TRUE
J 0
(1400 -25);
DISPLAY 1.170213 (1400 -25);
PAINT GREEN (1400 -25);
DISPLAY INVISIBLE (1400 -25);
FORCEPROP 2 LAST PATH I52
J 0
(1025 100);
DISPLAY 0.680851 (1025 100);
DISPLAY INVISIBLE (1025 100);
FORCEADD OFFPAGE..2
R 2
(1300 100);
FORCEPROP 2 LAST $XR0 275 
J 0
(1045 100);
DISPLAY 0.638298 (1045 100);
PAINT MONO (1045 100);
FORCEPROP 2 LAST CDS_LIB standard
J 0
(1300 100);
DISPLAY INVISIBLE (1300 100);
FORCEPROP 1 LAST OFFPAGE TRUE
J 2
(975 -25);
DISPLAY 0.872340 (975 -25);
PAINT AQUA (975 -25);
DISPLAY INVISIBLE (975 -25);
FORCEPROP 1 LAST COMMENT_BODY TRUE
J 2
(1345 5);
DISPLAY 0.872340 (1345 5);
PAINT GREEN (1345 5);
DISPLAY INVISIBLE (1345 5);
FORCEPROP 2 LAST PATH I53
J 0
(1025 150);
DISPLAY 0.680851 (1025 150);
DISPLAY INVISIBLE (1025 150);
FORCEADD OFFPAGE..1
(1275 350);
FORCEPROP 2 LAST $XR0 287 
J 0
(993 350);
DISPLAY 0.638298 (993 350);
PAINT MONO (993 350);
FORCEPROP 2 LAST CDS_LIB standard
J 0
(1275 350);
DISPLAY INVISIBLE (1275 350);
FORCEPROP 1 LAST OFFPAGE TRUE
J 0
(1600 225);
DISPLAY 0.872340 (1600 225);
PAINT AQUA (1600 225);
DISPLAY INVISIBLE (1600 225);
FORCEPROP 1 LAST COMMENT_BODY TRUE
J 0
(1400 250);
DISPLAY 0.872340 (1400 250);
PAINT GREEN (1400 250);
DISPLAY INVISIBLE (1400 250);
FORCEPROP 2 LAST PATH I54
J 0
(1025 400);
DISPLAY 0.680851 (1025 400);
DISPLAY INVISIBLE (1025 400);
FORCEADD OFFPAGE..1
(1275 400);
FORCEPROP 2 LAST $XR0 287 
J 0
(993 400);
DISPLAY 0.638298 (993 400);
PAINT MONO (993 400);
FORCEPROP 2 LAST CDS_LIB standard
J 0
(1275 400);
DISPLAY INVISIBLE (1275 400);
FORCEPROP 1 LAST OFFPAGE TRUE
J 0
(1600 275);
DISPLAY 0.872340 (1600 275);
PAINT AQUA (1600 275);
DISPLAY INVISIBLE (1600 275);
FORCEPROP 1 LAST COMMENT_BODY TRUE
J 0
(1400 300);
DISPLAY 0.872340 (1400 300);
PAINT GREEN (1400 300);
DISPLAY INVISIBLE (1400 300);
FORCEPROP 2 LAST PATH I55
J 0
(1025 450);
DISPLAY 0.680851 (1025 450);
DISPLAY INVISIBLE (1025 450);
FORCEADD OFFPAGE..1
(1275 550);
FORCEPROP 2 LAST $XR0 276 
J 0
(993 550);
DISPLAY 0.638298 (993 550);
PAINT MONO (993 550);
FORCEPROP 2 LAST CDS_LIB standard
J 0
(1275 550);
DISPLAY INVISIBLE (1275 550);
FORCEPROP 1 LAST OFFPAGE TRUE
J 0
(1600 425);
DISPLAY 0.872340 (1600 425);
PAINT AQUA (1600 425);
DISPLAY INVISIBLE (1600 425);
FORCEPROP 1 LAST COMMENT_BODY TRUE
J 0
(1400 450);
DISPLAY 0.872340 (1400 450);
PAINT GREEN (1400 450);
DISPLAY INVISIBLE (1400 450);
FORCEPROP 2 LAST PATH I56
J 0
(1000 600);
DISPLAY 0.680851 (1000 600);
DISPLAY INVISIBLE (1000 600);
FORCEADD OFFPAGE..1
(1275 500);
FORCEPROP 2 LAST $XR0 276 
J 0
(993 500);
DISPLAY 0.638298 (993 500);
PAINT MONO (993 500);
FORCEPROP 2 LAST CDS_LIB standard
J 0
(1275 500);
DISPLAY INVISIBLE (1275 500);
FORCEPROP 1 LAST OFFPAGE TRUE
J 0
(1600 375);
DISPLAY 0.872340 (1600 375);
PAINT AQUA (1600 375);
DISPLAY INVISIBLE (1600 375);
FORCEPROP 1 LAST COMMENT_BODY TRUE
J 0
(1400 400);
DISPLAY 0.872340 (1400 400);
PAINT GREEN (1400 400);
DISPLAY INVISIBLE (1400 400);
FORCEPROP 2 LAST PATH I57
J 0
(1000 550);
DISPLAY 0.680851 (1000 550);
DISPLAY INVISIBLE (1000 550);
FORCEADD OFFPAGE..2
R 2
(1275 700);
FORCEPROP 2 LAST $XR0 286 
J 0
(1020 700);
DISPLAY 0.638298 (1020 700);
PAINT MONO (1020 700);
FORCEPROP 2 LAST CDS_LIB standard
J 0
(1275 700);
DISPLAY INVISIBLE (1275 700);
FORCEPROP 1 LAST OFFPAGE TRUE
J 2
(950 575);
DISPLAY 0.872340 (950 575);
PAINT AQUA (950 575);
DISPLAY INVISIBLE (950 575);
FORCEPROP 1 LAST COMMENT_BODY TRUE
J 2
(1320 605);
DISPLAY 0.872340 (1320 605);
PAINT GREEN (1320 605);
DISPLAY INVISIBLE (1320 605);
FORCEPROP 2 LAST PATH I58
J 0
(1025 750);
DISPLAY 0.680851 (1025 750);
DISPLAY INVISIBLE (1025 750);
FORCEADD OFFPAGE..5
(1275 650);
FORCEPROP 2 LAST $XR0 286 
J 0
(1020 650);
DISPLAY 0.638298 (1020 650);
PAINT MONO (1020 650);
FORCEPROP 2 LAST CDS_LIB standard
J 0
(1275 650);
DISPLAY INVISIBLE (1275 650);
FORCEPROP 1 LAST OFFPAGE TRUE
J 0
(1600 525);
DISPLAY 0.872340 (1600 525);
PAINT AQUA (1600 525);
DISPLAY INVISIBLE (1600 525);
FORCEPROP 1 LAST COMMENT_BODY TRUE
J 0
(1375 575);
DISPLAY 1.170213 (1375 575);
PAINT GREEN (1375 575);
DISPLAY INVISIBLE (1375 575);
FORCEPROP 2 LAST PATH I59
J 0
(1025 700);
DISPLAY 0.680851 (1025 700);
DISPLAY INVISIBLE (1025 700);
FORCEADD OFFPAGE..2
R 2
(-3200 -900);
FORCEPROP 2 LAST $XR0 286 
J 0
(-3455 -900);
DISPLAY 0.638298 (-3455 -900);
PAINT MONO (-3455 -900);
FORCEPROP 2 LAST CDS_LIB standard
J 0
(-3200 -900);
DISPLAY INVISIBLE (-3200 -900);
FORCEPROP 1 LAST OFFPAGE TRUE
J 2
(-3525 -1025);
DISPLAY 0.872340 (-3525 -1025);
PAINT AQUA (-3525 -1025);
DISPLAY INVISIBLE (-3525 -1025);
FORCEPROP 1 LAST COMMENT_BODY TRUE
J 2
(-3155 -995);
DISPLAY 0.872340 (-3155 -995);
PAINT GREEN (-3155 -995);
DISPLAY INVISIBLE (-3155 -995);
FORCEPROP 2 LAST PATH I6
J 0
(-3475 -850);
DISPLAY 0.680851 (-3475 -850);
DISPLAY INVISIBLE (-3475 -850);
FORCEADD OFFPAGE..5
(1275 800);
FORCEPROP 2 LAST $XR0 275 
J 0
(1020 800);
DISPLAY 0.638298 (1020 800);
PAINT MONO (1020 800);
FORCEPROP 2 LAST CDS_LIB standard
J 0
(1275 800);
DISPLAY INVISIBLE (1275 800);
FORCEPROP 1 LAST OFFPAGE TRUE
J 0
(1600 675);
DISPLAY 0.872340 (1600 675);
PAINT AQUA (1600 675);
DISPLAY INVISIBLE (1600 675);
FORCEPROP 1 LAST COMMENT_BODY TRUE
J 0
(1375 725);
DISPLAY 1.170213 (1375 725);
PAINT GREEN (1375 725);
DISPLAY INVISIBLE (1375 725);
FORCEPROP 2 LAST PATH I60
J 0
(1025 850);
DISPLAY 0.680851 (1025 850);
DISPLAY INVISIBLE (1025 850);
FORCEADD OFFPAGE..2
R 2
(1275 850);
FORCEPROP 2 LAST $XR0 275 
J 0
(1020 850);
DISPLAY 0.638298 (1020 850);
PAINT MONO (1020 850);
FORCEPROP 2 LAST CDS_LIB standard
J 0
(1275 850);
DISPLAY INVISIBLE (1275 850);
FORCEPROP 1 LAST OFFPAGE TRUE
J 2
(950 725);
DISPLAY 0.872340 (950 725);
PAINT AQUA (950 725);
DISPLAY INVISIBLE (950 725);
FORCEPROP 1 LAST COMMENT_BODY TRUE
J 2
(1320 755);
DISPLAY 0.872340 (1320 755);
PAINT GREEN (1320 755);
DISPLAY INVISIBLE (1320 755);
FORCEPROP 2 LAST PATH I61
J 0
(1025 900);
DISPLAY 0.680851 (1025 900);
DISPLAY INVISIBLE (1025 900);
FORCEADD OFFPAGE..1
(1275 1250);
FORCEPROP 2 LAST $XR0 287 
J 0
(993 1250);
DISPLAY 0.638298 (993 1250);
PAINT MONO (993 1250);
FORCEPROP 2 LAST CDS_LIB standard
J 0
(1275 1250);
DISPLAY INVISIBLE (1275 1250);
FORCEPROP 1 LAST OFFPAGE TRUE
J 0
(1600 1125);
DISPLAY 0.872340 (1600 1125);
PAINT AQUA (1600 1125);
DISPLAY INVISIBLE (1600 1125);
FORCEPROP 1 LAST COMMENT_BODY TRUE
J 0
(1400 1150);
DISPLAY 0.872340 (1400 1150);
PAINT GREEN (1400 1150);
DISPLAY INVISIBLE (1400 1150);
FORCEPROP 2 LAST PATH I62
J 0
(1025 1300);
DISPLAY 0.680851 (1025 1300);
DISPLAY INVISIBLE (1025 1300);
FORCEADD OFFPAGE..1
(1275 1200);
FORCEPROP 2 LAST $XR0 287 
J 0
(993 1200);
DISPLAY 0.638298 (993 1200);
PAINT MONO (993 1200);
FORCEPROP 2 LAST CDS_LIB standard
J 0
(1275 1200);
DISPLAY INVISIBLE (1275 1200);
FORCEPROP 1 LAST OFFPAGE TRUE
J 0
(1600 1075);
DISPLAY 0.872340 (1600 1075);
PAINT AQUA (1600 1075);
DISPLAY INVISIBLE (1600 1075);
FORCEPROP 1 LAST COMMENT_BODY TRUE
J 0
(1400 1100);
DISPLAY 0.872340 (1400 1100);
PAINT GREEN (1400 1100);
DISPLAY INVISIBLE (1400 1100);
FORCEPROP 2 LAST PATH I63
J 0
(1025 1250);
DISPLAY 0.680851 (1025 1250);
DISPLAY INVISIBLE (1025 1250);
FORCEADD OFFPAGE..1
(1275 1400);
FORCEPROP 2 LAST $XR0 276 
J 0
(993 1400);
DISPLAY 0.638298 (993 1400);
PAINT MONO (993 1400);
FORCEPROP 2 LAST CDS_LIB standard
J 0
(1275 1400);
DISPLAY INVISIBLE (1275 1400);
FORCEPROP 1 LAST OFFPAGE TRUE
J 0
(1600 1275);
DISPLAY 0.872340 (1600 1275);
PAINT AQUA (1600 1275);
DISPLAY INVISIBLE (1600 1275);
FORCEPROP 1 LAST COMMENT_BODY TRUE
J 0
(1400 1300);
DISPLAY 0.872340 (1400 1300);
PAINT GREEN (1400 1300);
DISPLAY INVISIBLE (1400 1300);
FORCEPROP 2 LAST PATH I64
J 0
(1025 1450);
DISPLAY 0.680851 (1025 1450);
DISPLAY INVISIBLE (1025 1450);
FORCEADD OFFPAGE..5
(1275 1500);
FORCEPROP 2 LAST $XR0 286 
J 0
(1020 1500);
DISPLAY 0.638298 (1020 1500);
PAINT MONO (1020 1500);
FORCEPROP 2 LAST CDS_LIB standard
J 0
(1275 1500);
DISPLAY INVISIBLE (1275 1500);
FORCEPROP 1 LAST OFFPAGE TRUE
J 0
(1600 1375);
DISPLAY 0.872340 (1600 1375);
PAINT AQUA (1600 1375);
DISPLAY INVISIBLE (1600 1375);
FORCEPROP 1 LAST COMMENT_BODY TRUE
J 0
(1375 1425);
DISPLAY 1.170213 (1375 1425);
PAINT GREEN (1375 1425);
DISPLAY INVISIBLE (1375 1425);
FORCEPROP 2 LAST PATH I65
J 0
(1025 1550);
DISPLAY 0.680851 (1025 1550);
DISPLAY INVISIBLE (1025 1550);
FORCEADD OFFPAGE..2
R 2
(1275 1550);
FORCEPROP 2 LAST $XR0 286 
J 0
(1020 1550);
DISPLAY 0.638298 (1020 1550);
PAINT MONO (1020 1550);
FORCEPROP 2 LAST CDS_LIB standard
J 0
(1275 1550);
DISPLAY INVISIBLE (1275 1550);
FORCEPROP 1 LAST OFFPAGE TRUE
J 2
(950 1425);
DISPLAY 0.872340 (950 1425);
PAINT AQUA (950 1425);
DISPLAY INVISIBLE (950 1425);
FORCEPROP 1 LAST COMMENT_BODY TRUE
J 2
(1320 1455);
DISPLAY 0.872340 (1320 1455);
PAINT GREEN (1320 1455);
DISPLAY INVISIBLE (1320 1455);
FORCEPROP 2 LAST PATH I66
J 0
(1025 1600);
DISPLAY 0.680851 (1025 1600);
DISPLAY INVISIBLE (1025 1600);
FORCEADD OFFPAGE..5
(1275 1650);
FORCEPROP 2 LAST $XR0 275 
J 0
(1020 1650);
DISPLAY 0.638298 (1020 1650);
PAINT MONO (1020 1650);
FORCEPROP 2 LAST CDS_LIB standard
J 0
(1275 1650);
DISPLAY INVISIBLE (1275 1650);
FORCEPROP 1 LAST OFFPAGE TRUE
J 0
(1600 1525);
DISPLAY 0.872340 (1600 1525);
PAINT AQUA (1600 1525);
DISPLAY INVISIBLE (1600 1525);
FORCEPROP 1 LAST COMMENT_BODY TRUE
J 0
(1375 1575);
DISPLAY 1.170213 (1375 1575);
PAINT GREEN (1375 1575);
DISPLAY INVISIBLE (1375 1575);
FORCEPROP 2 LAST PATH I67
J 0
(1025 1700);
DISPLAY 0.680851 (1025 1700);
DISPLAY INVISIBLE (1025 1700);
FORCEADD OFFPAGE..2
R 2
(1275 1700);
FORCEPROP 2 LAST $XR0 275 
J 0
(1020 1700);
DISPLAY 0.638298 (1020 1700);
PAINT MONO (1020 1700);
FORCEPROP 2 LAST CDS_LIB standard
J 0
(1275 1700);
DISPLAY INVISIBLE (1275 1700);
FORCEPROP 1 LAST OFFPAGE TRUE
J 2
(950 1575);
DISPLAY 0.872340 (950 1575);
PAINT AQUA (950 1575);
DISPLAY INVISIBLE (950 1575);
FORCEPROP 1 LAST COMMENT_BODY TRUE
J 2
(1320 1605);
DISPLAY 0.872340 (1320 1605);
PAINT GREEN (1320 1605);
DISPLAY INVISIBLE (1320 1605);
FORCEPROP 2 LAST PATH I68
J 0
(1025 1750);
DISPLAY 0.680851 (1025 1750);
DISPLAY INVISIBLE (1025 1750);
FORCEADD OFFPAGE..1
(1275 1350);
FORCEPROP 2 LAST $XR0 276 
J 0
(993 1350);
DISPLAY 0.638298 (993 1350);
PAINT MONO (993 1350);
FORCEPROP 2 LAST CDS_LIB standard
J 0
(1275 1350);
DISPLAY INVISIBLE (1275 1350);
FORCEPROP 1 LAST OFFPAGE TRUE
J 0
(1600 1225);
DISPLAY 0.872340 (1600 1225);
PAINT AQUA (1600 1225);
DISPLAY INVISIBLE (1600 1225);
FORCEPROP 1 LAST COMMENT_BODY TRUE
J 0
(1400 1250);
DISPLAY 0.872340 (1400 1250);
PAINT GREEN (1400 1250);
DISPLAY INVISIBLE (1400 1250);
FORCEPROP 2 LAST PATH I69
J 0
(1025 1400);
DISPLAY 0.680851 (1025 1400);
DISPLAY INVISIBLE (1025 1400);
FORCEADD OFFPAGE..5
(-3200 -800);
FORCEPROP 2 LAST $XR0 275 
J 0
(-3455 -800);
DISPLAY 0.638298 (-3455 -800);
PAINT MONO (-3455 -800);
FORCEPROP 2 LAST CDS_LIB standard
J 0
(-3200 -800);
DISPLAY INVISIBLE (-3200 -800);
FORCEPROP 1 LAST OFFPAGE TRUE
J 0
(-2875 -925);
DISPLAY 0.872340 (-2875 -925);
PAINT AQUA (-2875 -925);
DISPLAY INVISIBLE (-2875 -925);
FORCEPROP 1 LAST COMMENT_BODY TRUE
J 0
(-3100 -875);
DISPLAY 1.170213 (-3100 -875);
PAINT GREEN (-3100 -875);
DISPLAY INVISIBLE (-3100 -875);
FORCEPROP 2 LAST PATH I7
J 0
(-3475 -750);
DISPLAY 0.680851 (-3475 -750);
DISPLAY INVISIBLE (-3475 -750);
FORCEADD CONN112_10137002101LF..1
(-1000 250);
FORCEPROP 1 LAST LOCATION J107
J 0
(-1750 2050);
DISPLAY 0.723404 (-1750 2050);
PAINT GREEN (-1750 2050);
FORCEPROP 0 LAST $SEC 1
J 0
(-1750 2175);
DISPLAY 0.680851 (-1750 2175);
PAINT MONO (-1750 2175);
DISPLAY INVISIBLE (-1750 2175);
FORCEPROP 0 LAST CDS_SEC 1
J 0
(-1750 2175);
DISPLAY 1.021277 (-1750 2175);
DISPLAY INVISIBLE (-1750 2175);
FORCEPROP 0 LASTPIN (-1925 -650) $PN A5
J 2
(-1935 -640);
DISPLAY 0.680851 (-1935 -640);
PAINT MONO (-1935 -640);
FORCEPROP 0 LASTPIN (-1925 150) $PN A6
J 2
(-1935 160);
DISPLAY 0.680851 (-1935 160);
PAINT MONO (-1935 160);
FORCEPROP 0 LASTPIN (-1925 950) $PN A7
J 2
(-1935 960);
DISPLAY 0.680851 (-1935 960);
PAINT MONO (-1935 960);
FORCEPROP 0 LASTPIN (-1925 1750) $PN A8
J 2
(-1935 1760);
DISPLAY 0.680851 (-1935 1760);
PAINT MONO (-1935 1760);
FORCEPROP 0 LASTPIN (-1925 -700) $PN B5
J 2
(-1935 -690);
DISPLAY 0.680851 (-1935 -690);
PAINT MONO (-1935 -690);
FORCEPROP 0 LASTPIN (-1925 100) $PN B6
J 2
(-1935 110);
DISPLAY 0.680851 (-1935 110);
PAINT MONO (-1935 110);
FORCEPROP 0 LASTPIN (-1925 900) $PN B7
J 2
(-1935 910);
DISPLAY 0.680851 (-1935 910);
PAINT MONO (-1935 910);
FORCEPROP 0 LASTPIN (-1925 1700) $PN B8
J 2
(-1935 1710);
DISPLAY 0.680851 (-1935 1710);
PAINT MONO (-1935 1710);
FORCEPROP 0 LASTPIN (-1925 -750) $PN C5
J 2
(-1935 -740);
DISPLAY 0.680851 (-1935 -740);
PAINT MONO (-1935 -740);
FORCEPROP 0 LASTPIN (-1925 50) $PN C6
J 2
(-1935 60);
DISPLAY 0.680851 (-1935 60);
PAINT MONO (-1935 60);
FORCEPROP 0 LASTPIN (-1925 850) $PN C7
J 2
(-1935 860);
DISPLAY 0.680851 (-1935 860);
PAINT MONO (-1935 860);
FORCEPROP 0 LASTPIN (-1925 1650) $PN C8
J 2
(-1935 1660);
DISPLAY 0.680851 (-1935 1660);
PAINT MONO (-1935 1660);
FORCEPROP 0 LASTPIN (-1925 -800) $PN D5
J 2
(-1935 -790);
DISPLAY 0.680851 (-1935 -790);
PAINT MONO (-1935 -790);
FORCEPROP 0 LASTPIN (-1925 0) $PN D6
J 2
(-1935 10);
DISPLAY 0.680851 (-1935 10);
PAINT MONO (-1935 10);
FORCEPROP 0 LASTPIN (-1925 800) $PN D7
J 2
(-1935 810);
DISPLAY 0.680851 (-1935 810);
PAINT MONO (-1935 810);
FORCEPROP 0 LASTPIN (-1925 1600) $PN D8
J 2
(-1935 1610);
DISPLAY 0.680851 (-1935 1610);
PAINT MONO (-1935 1610);
FORCEPROP 0 LASTPIN (-1925 -850) $PN E5
J 2
(-1935 -840);
DISPLAY 0.680851 (-1935 -840);
PAINT MONO (-1935 -840);
FORCEPROP 0 LASTPIN (-1925 -50) $PN E6
J 2
(-1935 -40);
DISPLAY 0.680851 (-1935 -40);
PAINT MONO (-1935 -40);
FORCEPROP 0 LASTPIN (-1925 750) $PN E7
J 2
(-1935 760);
DISPLAY 0.680851 (-1935 760);
PAINT MONO (-1935 760);
FORCEPROP 0 LASTPIN (-1925 1550) $PN E8
J 2
(-1935 1560);
DISPLAY 0.680851 (-1935 1560);
PAINT MONO (-1935 1560);
FORCEPROP 0 LASTPIN (-1925 -900) $PN F5
J 2
(-1935 -890);
DISPLAY 0.680851 (-1935 -890);
PAINT MONO (-1935 -890);
FORCEPROP 0 LASTPIN (-1925 -100) $PN F6
J 2
(-1935 -90);
DISPLAY 0.680851 (-1935 -90);
PAINT MONO (-1935 -90);
FORCEPROP 0 LASTPIN (-1925 700) $PN F7
J 2
(-1935 710);
DISPLAY 0.680851 (-1935 710);
PAINT MONO (-1935 710);
FORCEPROP 0 LASTPIN (-1925 1500) $PN F8
J 2
(-1935 1510);
DISPLAY 0.680851 (-1935 1510);
PAINT MONO (-1935 1510);
FORCEPROP 0 LASTPIN (-1925 -950) $PN G5
J 2
(-1935 -940);
DISPLAY 0.680851 (-1935 -940);
PAINT MONO (-1935 -940);
FORCEPROP 0 LASTPIN (-1925 -150) $PN G6
J 2
(-1935 -140);
DISPLAY 0.680851 (-1935 -140);
PAINT MONO (-1935 -140);
FORCEPROP 0 LASTPIN (-1925 650) $PN G7
J 2
(-1935 660);
DISPLAY 0.680851 (-1935 660);
PAINT MONO (-1935 660);
FORCEPROP 0 LASTPIN (-1925 1450) $PN G8
J 2
(-1935 1460);
DISPLAY 0.680851 (-1935 1460);
PAINT MONO (-1935 1460);
FORCEPROP 0 LASTPIN (-1925 -1000) $PN H5
J 2
(-1935 -990);
DISPLAY 0.680851 (-1935 -990);
PAINT MONO (-1935 -990);
FORCEPROP 0 LASTPIN (-1925 -200) $PN H6
J 2
(-1935 -190);
DISPLAY 0.680851 (-1935 -190);
PAINT MONO (-1935 -190);
FORCEPROP 0 LASTPIN (-1925 600) $PN H7
J 2
(-1935 610);
DISPLAY 0.680851 (-1935 610);
PAINT MONO (-1935 610);
FORCEPROP 0 LASTPIN (-1925 1400) $PN H8
J 2
(-1935 1410);
DISPLAY 0.680851 (-1935 1410);
PAINT MONO (-1935 1410);
FORCEPROP 0 LASTPIN (-1925 -1050) $PN I5
J 2
(-1935 -1040);
DISPLAY 0.680851 (-1935 -1040);
PAINT MONO (-1935 -1040);
FORCEPROP 0 LASTPIN (-1925 -250) $PN I6
J 2
(-1935 -240);
DISPLAY 0.680851 (-1935 -240);
PAINT MONO (-1935 -240);
FORCEPROP 0 LASTPIN (-1925 550) $PN I7
J 2
(-1935 560);
DISPLAY 0.680851 (-1935 560);
PAINT MONO (-1935 560);
FORCEPROP 0 LASTPIN (-1925 1350) $PN I8
J 2
(-1935 1360);
DISPLAY 0.680851 (-1935 1360);
PAINT MONO (-1935 1360);
FORCEPROP 0 LASTPIN (-1925 -1100) $PN J5
J 2
(-1935 -1090);
DISPLAY 0.680851 (-1935 -1090);
PAINT MONO (-1935 -1090);
FORCEPROP 0 LASTPIN (-1925 -300) $PN J6
J 2
(-1935 -290);
DISPLAY 0.680851 (-1935 -290);
PAINT MONO (-1935 -290);
FORCEPROP 0 LASTPIN (-1925 500) $PN J7
J 2
(-1935 510);
DISPLAY 0.680851 (-1935 510);
PAINT MONO (-1935 510);
FORCEPROP 0 LASTPIN (-1925 1300) $PN J8
J 2
(-1935 1310);
DISPLAY 0.680851 (-1935 1310);
PAINT MONO (-1935 1310);
FORCEPROP 0 LASTPIN (-1925 -1150) $PN K5
J 2
(-1935 -1140);
DISPLAY 0.680851 (-1935 -1140);
PAINT MONO (-1935 -1140);
FORCEPROP 0 LASTPIN (-1925 -350) $PN K6
J 2
(-1935 -340);
DISPLAY 0.680851 (-1935 -340);
PAINT MONO (-1935 -340);
FORCEPROP 0 LASTPIN (-1925 450) $PN K7
J 2
(-1935 460);
DISPLAY 0.680851 (-1935 460);
PAINT MONO (-1935 460);
FORCEPROP 0 LASTPIN (-1925 1250) $PN K8
J 2
(-1935 1260);
DISPLAY 0.680851 (-1935 1260);
PAINT MONO (-1935 1260);
FORCEPROP 0 LASTPIN (-1925 -1200) $PN L5
J 2
(-1935 -1190);
DISPLAY 0.680851 (-1935 -1190);
PAINT MONO (-1935 -1190);
FORCEPROP 0 LASTPIN (-1925 -400) $PN L6
J 2
(-1935 -390);
DISPLAY 0.680851 (-1935 -390);
PAINT MONO (-1935 -390);
FORCEPROP 0 LASTPIN (-1925 400) $PN L7
J 2
(-1935 410);
DISPLAY 0.680851 (-1935 410);
PAINT MONO (-1935 410);
FORCEPROP 0 LASTPIN (-1925 1200) $PN L8
J 2
(-1935 1210);
DISPLAY 0.680851 (-1935 1210);
PAINT MONO (-1935 1210);
FORCEPROP 0 LASTPIN (-1925 -1250) $PN M5
J 2
(-1935 -1240);
DISPLAY 0.680851 (-1935 -1240);
PAINT MONO (-1935 -1240);
FORCEPROP 0 LASTPIN (-1925 -450) $PN M6
J 2
(-1935 -440);
DISPLAY 0.680851 (-1935 -440);
PAINT MONO (-1935 -440);
FORCEPROP 0 LASTPIN (-1925 350) $PN M7
J 2
(-1935 360);
DISPLAY 0.680851 (-1935 360);
PAINT MONO (-1935 360);
FORCEPROP 0 LASTPIN (-1925 1150) $PN M8
J 2
(-1935 1160);
DISPLAY 0.680851 (-1935 1160);
PAINT MONO (-1935 1160);
FORCEPROP 0 LASTPIN (-1925 -1300) $PN N5
J 2
(-1935 -1290);
DISPLAY 0.680851 (-1935 -1290);
PAINT MONO (-1935 -1290);
FORCEPROP 0 LASTPIN (-1925 -500) $PN N6
J 2
(-1935 -490);
DISPLAY 0.680851 (-1935 -490);
PAINT MONO (-1935 -490);
FORCEPROP 0 LASTPIN (-1925 300) $PN N7
J 2
(-1935 310);
DISPLAY 0.680851 (-1935 310);
PAINT MONO (-1935 310);
FORCEPROP 0 LASTPIN (-1925 1100) $PN N8
J 2
(-1935 1110);
DISPLAY 0.680851 (-1935 1110);
PAINT MONO (-1935 1110);
FORCEPROP 1 LAST MATERIAL IO
J 0
(-1745 1932);
DISPLAY 0.723404 (-1745 1932);
PAINT GREEN (-1745 1932);
FORCEPROP 2 LAST PART_TYPE THLF
J 0
(-1750 2125);
DISPLAY 1.021277 (-1750 2125);
FORCEPROP 2 LAST CDS_LIB pure_quanta
J 0
(-1000 250);
DISPLAY INVISIBLE (-1000 250);
FORCEPROP 1 LAST CDS_LMAN_SYM_OUTLINE -775,1650,775,-1650
J 0
(-1000 250);
DISPLAY 0.468085 (-1000 250);
PAINT GREEN (-1000 250);
DISPLAY INVISIBLE (-1000 250);
FORCEPROP 1 LAST NEEDS_NO_SIZE TRUE
J 0
(-1000 250);
DISPLAY 0.723404 (-1000 250);
PAINT GREEN (-1000 250);
DISPLAY INVISIBLE (-1000 250);
FORCEPROP 0 LAST VALUE CONN112_10137002-101LF
J 0
(-1725 2250);
DISPLAY 1.021277 (-1725 2250);
DISPLAY INVISIBLE (-1725 2250);
FORCEPROP 1 LAST PATH I70
J 0
(-1000 250);
DISPLAY 0.723404 (-1000 250);
PAINT GREEN (-1000 250);
DISPLAY INVISIBLE (-1000 250);
FORCEPROP 1 LAST PART_NUMBER DFHSB2FR012
J 0
(-1750 2000);
DISPLAY 0.723404 (-1750 2000);
PAINT GREEN (-1750 2000);
DISPLAY INVISIBLE (-1750 2000);
FORCEADD OFFPAGE..2
R 2
(1300 -500);
FORCEPROP 2 LAST $XR0 123 
J 0
(1045 -500);
DISPLAY 0.638298 (1045 -500);
PAINT MONO (1045 -500);
FORCEPROP 2 LAST CDS_LIB standard
J 0
(1300 -500);
DISPLAY INVISIBLE (1300 -500);
FORCEPROP 1 LAST OFFPAGE TRUE
J 2
(975 -625);
DISPLAY 0.872340 (975 -625);
PAINT AQUA (975 -625);
DISPLAY INVISIBLE (975 -625);
FORCEPROP 1 LAST COMMENT_BODY TRUE
J 2
(1345 -595);
DISPLAY 0.872340 (1345 -595);
PAINT GREEN (1345 -595);
DISPLAY INVISIBLE (1345 -595);
FORCEPROP 2 LAST PATH I71
J 0
(1350 -425);
DISPLAY 0.680851 (1350 -425);
DISPLAY INVISIBLE (1350 -425);
FORCEADD OFFPAGE..2
R 2
(-3200 -750);
FORCEPROP 2 LAST $XR0 275 
J 0
(-3455 -750);
DISPLAY 0.638298 (-3455 -750);
PAINT MONO (-3455 -750);
FORCEPROP 2 LAST CDS_LIB standard
J 0
(-3200 -750);
DISPLAY INVISIBLE (-3200 -750);
FORCEPROP 1 LAST OFFPAGE TRUE
J 2
(-3525 -875);
DISPLAY 0.872340 (-3525 -875);
PAINT AQUA (-3525 -875);
DISPLAY INVISIBLE (-3525 -875);
FORCEPROP 1 LAST COMMENT_BODY TRUE
J 2
(-3155 -845);
DISPLAY 0.872340 (-3155 -845);
PAINT GREEN (-3155 -845);
DISPLAY INVISIBLE (-3155 -845);
FORCEPROP 2 LAST PATH I8
J 0
(-3475 -700);
DISPLAY 0.680851 (-3475 -700);
DISPLAY INVISIBLE (-3475 -700);
FORCEADD OFFPAGE..1
(-3200 -400);
FORCEPROP 2 LAST $XR0 287 
J 0
(-3452 -400);
DISPLAY 0.638298 (-3452 -400);
PAINT MONO (-3452 -400);
FORCEPROP 2 LAST CDS_LIB standard
J 0
(-3200 -400);
DISPLAY INVISIBLE (-3200 -400);
FORCEPROP 1 LAST OFFPAGE TRUE
J 0
(-2875 -525);
DISPLAY 0.872340 (-2875 -525);
PAINT AQUA (-2875 -525);
DISPLAY INVISIBLE (-2875 -525);
FORCEPROP 1 LAST COMMENT_BODY TRUE
J 0
(-3075 -500);
DISPLAY 0.872340 (-3075 -500);
PAINT GREEN (-3075 -500);
DISPLAY INVISIBLE (-3075 -500);
FORCEPROP 2 LAST PATH I9
J 0
(-3450 -350);
DISPLAY 0.680851 (-3450 -350);
DISPLAY INVISIBLE (-3450 -350);
FORCEADD QUANTA_TITLE_BLOCK_C..1
(4700 -3400);
FORCEPROP 0 LAST CDS_CON_LAST_MODIFIED Thu Sep 14 16:12:58 2023
J 0
(2815 -3385);
PAINT MONO (2815 -3385);
DISPLAY INVISIBLE (2815 -3385);
FORCEPROP 2 LAST CUSTOM_TXT_CDS <XR_PAGE_TITLE>
J 0
(-3190 1850);
DISPLAY 0.638298 (-3190 1850);
PAINT PINK (-3190 1850);
DISPLAY INVISIBLE (-3190 1850);
FORCEPROP 2 LAST CUSTOM_TXT_CDS <CON_LAST_MODIFIED>
J 0
(2825 -3400);
DISPLAY 0.978723 (2825 -3400);
FORCEPROP 2 LAST CUSTOM_TXT_CDS <Q_NUMBER>
J 0
(3297 -3297);
DISPLAY 1.212766 (3297 -3297);
FORCEPROP 2 LAST CUSTOM_TXT_CDS <Q_REV>
J 0
(4516 -3297);
DISPLAY 1.212766 (4516 -3297);
FORCEPROP 2 LAST CUSTOM_TXT_CDS <NAME_2>
J 0
(1525 -3350);
FORCEPROP 2 LAST CUSTOM_TXT_CDS <NAME_1>
J 0
(1525 -3225);
FORCEPROP 2 LAST CUSTOM_TXT_CDS <Q_PROJ>
J 0
(2318 -3298);
DISPLAY 1.212766 (2318 -3298);
FORCEPROP 1 LAST CUSTOM_TXT_CDS <CON_PAGE_NUM> OF <CON_TOTAL_PAGES>
J 0
(4254 -3382);
DISPLAY 0.978723 (4254 -3382);
FORCEPROP 1 LAST Q_TITLE PCIE - CPU0_EXAMAX_P0/P1_X16
J 0
(-4575 -3350);
DISPLAY 1.957447 (-4575 -3350);
PAINT GREEN (-4575 -3350);
FORCEPROP 1 LAST CDS_LMAN_SYM_OUTLINE -9475,6775,100,-125
J 0
(4700 -3400);
DISPLAY 0.468085 (4700 -3400);
PAINT GREEN (4700 -3400);
DISPLAY INVISIBLE (4700 -3400);
FORCEPROP 2 LAST CDS_LIB pure_quanta
J 0
(4700 -3400);
PAINT MONO (4700 -3400);
DISPLAY INVISIBLE (4700 -3400);
FORCEPROP 2 LAST PAGE_BORDER TRUE
J 0
(-3190 1850);
DISPLAY 0.638298 (-3190 1850);
PAINT PINK (-3190 1850);
DISPLAY INVISIBLE (-3190 1850);
FORCEPROP 2 LAST CDS_XR_PAGE_TITLE CR-117 : @T6G_MB_LIB.T6G(SCH_1):PAGE117
J 0
(-3190 1850);
DISPLAY 0.638298 (-3190 1850);
PAINT PINK (-3190 1850);
DISPLAY INVISIBLE (-3190 1850);
FORCEPROP 1 LAST Q_DEPT BU9
J 1
(937 -3351);
DISPLAY 1.957447 (937 -3351);
PAINT GREEN (937 -3351);
DISPLAY INVISIBLE (937 -3351);
FORCEPROP 1 LAST COMMENT_BODY TRUE
J 0
(4712 -3413);
DISPLAY 0.978723 (4712 -3413);
PAINT GREEN (4712 -3413);
DISPLAY INVISIBLE (4712 -3413);
WIRE 16 -1 (-1925 -400)(-3150 -400);
FORCEPROP 2 LAST SIG_NAME P5E_CPU0_P1_TX_BUF_C_DP<13>
J 0
(-2985 -390);
DISPLAY 0.638298 (-2985 -390);
WIRE 16 -1 (2575 -500)(1350 -500);
FORCEPROP 2 LAST SIG_NAME PRSNT_CABLE_SWB_B2_N
J 0
(1515 -490);
DISPLAY 0.638298 (1515 -490);
WIRE 16 -1 (2575 -650)(1350 -650);
FORCEPROP 2 LAST SIG_NAME NC_J107_A1
J 0
(1515 -640);
DISPLAY 0.638298 (1515 -640);
FORCEPROP 2 LASTPROP $XRERR UNIQUE?
J 0
(1110 -650);
DISPLAY 0.638298 (1110 -650);
PAINT MONO (1110 -650);
DISPLAY INVISIBLE (1110 -650);
WIRE 16 -1 (2575 -400)(1350 -400);
FORCEPROP 2 LAST SIG_NAME P5E_CPU0_P1_TX_BUF_C_DP<9>
J 0
(1490 -390);
DISPLAY 0.638298 (1490 -390);
WIRE 16 -1 (2575 -350)(1350 -350);
FORCEPROP 2 LAST SIG_NAME P5E_CPU0_P1_TX_BUF_C_DN<9>
J 0
(1490 -340);
DISPLAY 0.638298 (1490 -340);
WIRE 16 -1 (2575 1750)(2350 1750);
WIRE 16 -1 (2350 1750)(2350 1600);
WIRE 16 -1 (2575 1600)(2350 1600);
WIRE 16 -1 (2350 1600)(2350 1450);
WIRE 16 -1 (2575 1450)(2350 1450);
WIRE 16 -1 (2350 1450)(2350 1300);
WIRE 16 -1 (2575 1300)(2350 1300);
WIRE 16 -1 (2350 1300)(2350 1150);
WIRE 16 -1 (2575 1150)(2350 1150);
WIRE 16 -1 (2350 1150)(2350 900);
WIRE 16 -1 (2575 900)(2350 900);
WIRE 16 -1 (2350 900)(2350 750);
WIRE 16 -1 (2575 750)(2350 750);
WIRE 16 -1 (2350 750)(2350 600);
WIRE 16 -1 (2575 600)(2350 600);
WIRE 16 -1 (2350 600)(2350 450);
WIRE 16 -1 (2575 450)(2350 450);
WIRE 16 -1 (2350 450)(2350 300);
WIRE 16 -1 (2575 300)(2350 300);
WIRE 16 -1 (2350 300)(2350 150);
WIRE 16 -1 (2575 150)(2350 150);
WIRE 16 -1 (2350 150)(2350 0);
WIRE 16 -1 (2575 0)(2350 0);
WIRE 16 -1 (2350 0)(2350 -150);
WIRE 16 -1 (2575 -150)(2350 -150);
WIRE 16 -1 (2350 -150)(2350 -300);
WIRE 16 -1 (2575 -300)(2350 -300);
WIRE 16 -1 (2350 -300)(2350 -450);
WIRE 16 -1 (2575 -450)(2350 -450);
WIRE 16 -1 (2350 -450)(2350 -700);
WIRE 16 -1 (2575 -700)(2350 -700);
WIRE 16 -1 (2350 -700)(2350 -850);
WIRE 16 -1 (2575 -850)(2350 -850);
WIRE 16 -1 (2350 -850)(2350 -1000);
WIRE 16 -1 (2575 -1000)(2350 -1000);
WIRE 16 -1 (2350 -1000)(2350 -1150);
WIRE 16 -1 (2575 -1150)(2350 -1150);
WIRE 16 -1 (2350 -1150)(2350 -1300);
WIRE 16 -1 (2575 -1300)(2350 -1300);
WIRE 16 -1 (2350 -1300)(2350 -1650);
WIRE 16 -1 (2575 -250)(1350 -250);
FORCEPROP 2 LAST SIG_NAME P5E_CPU0_P0_TX_BUF_C_DP<9>
J 0
(1490 -240);
DISPLAY 0.638298 (1490 -240);
WIRE 16 -1 (2575 -100)(1350 -100);
FORCEPROP 2 LAST SIG_NAME P5E_CPU0_P1_RX_BUF_DP<9>
J 0
(1490 -90);
DISPLAY 0.638298 (1490 -90);
WIRE 16 -1 (2575 -50)(1350 -50);
FORCEPROP 2 LAST SIG_NAME P5E_CPU0_P1_RX_BUF_DN<9>
J 0
(1490 -40);
DISPLAY 0.638298 (1490 -40);
WIRE 16 -1 (2575 50)(1350 50);
FORCEPROP 2 LAST SIG_NAME P5E_CPU0_P0_RX_BUF_DP<9>
J 0
(1490 60);
DISPLAY 0.638298 (1490 60);
WIRE 16 -1 (2575 100)(1350 100);
FORCEPROP 2 LAST SIG_NAME P5E_CPU0_P0_RX_BUF_DN<9>
J 0
(1490 110);
DISPLAY 0.638298 (1490 110);
WIRE 16 -1 (2575 -750)(1350 -750);
FORCEPROP 2 LAST SIG_NAME P5E_CPU0_P0_RX_BUF_DN<8>
J 0
(1490 -740);
DISPLAY 0.638298 (1490 -740);
WIRE 16 -1 (2575 350)(1325 350);
FORCEPROP 2 LAST SIG_NAME P5E_CPU0_P1_TX_BUF_C_DP<10>
J 0
(1490 360);
DISPLAY 0.638298 (1490 360);
WIRE 16 -1 (2575 400)(1325 400);
FORCEPROP 2 LAST SIG_NAME P5E_CPU0_P1_TX_BUF_C_DN<10>
J 0
(1490 410);
DISPLAY 0.638298 (1490 410);
WIRE 16 -1 (2575 500)(1325 500);
FORCEPROP 2 LAST SIG_NAME P5E_CPU0_P0_TX_BUF_C_DP<10>
J 0
(1490 510);
DISPLAY 0.638298 (1490 510);
WIRE 16 -1 (2575 550)(1325 550);
FORCEPROP 2 LAST SIG_NAME P5E_CPU0_P0_TX_BUF_C_DN<10>
J 0
(1490 560);
DISPLAY 0.638298 (1490 560);
WIRE 16 -1 (2575 650)(1325 650);
FORCEPROP 2 LAST SIG_NAME P5E_CPU0_P1_RX_BUF_DP<10>
J 0
(1490 660);
DISPLAY 0.638298 (1490 660);
WIRE 16 -1 (2575 700)(1325 700);
FORCEPROP 2 LAST SIG_NAME P5E_CPU0_P1_RX_BUF_DN<10>
J 0
(1490 710);
DISPLAY 0.638298 (1490 710);
WIRE 16 -1 (2575 800)(1325 800);
FORCEPROP 2 LAST SIG_NAME P5E_CPU0_P0_RX_BUF_DP<10>
J 0
(1490 810);
DISPLAY 0.638298 (1490 810);
WIRE 16 -1 (2575 850)(1325 850);
FORCEPROP 2 LAST SIG_NAME P5E_CPU0_P0_RX_BUF_DN<10>
J 0
(1490 860);
DISPLAY 0.638298 (1490 860);
WIRE 16 -1 (2575 950)(1350 950);
FORCEPROP 2 LAST SIG_NAME NC_J107_A3
J 0
(1515 960);
DISPLAY 0.638298 (1515 960);
FORCEPROP 2 LASTPROP $XRERR UNIQUE?
J 0
(1110 950);
DISPLAY 0.638298 (1110 950);
PAINT MONO (1110 950);
DISPLAY INVISIBLE (1110 950);
WIRE 16 -1 (2575 1100)(1350 1100);
FORCEPROP 2 LAST SIG_NAME NC_J107_N4
J 0
(1515 1110);
DISPLAY 0.638298 (1515 1110);
FORCEPROP 2 LASTPROP $XRERR UNIQUE?
J 0
(1110 1100);
DISPLAY 0.638298 (1110 1100);
PAINT MONO (1110 1100);
DISPLAY INVISIBLE (1110 1100);
WIRE 16 -1 (-1925 800)(-3150 800);
FORCEPROP 2 LAST SIG_NAME P5E_CPU0_P0_RX_BUF_DP<14>
J 0
(-2985 810);
DISPLAY 0.638298 (-2985 810);
WIRE 16 -1 (-1925 850)(-3150 850);
FORCEPROP 2 LAST SIG_NAME P5E_CPU0_P0_RX_BUF_DN<14>
J 0
(-2985 860);
DISPLAY 0.638298 (-2985 860);
WIRE 16 -1 (-1925 950)(-3150 950);
FORCEPROP 2 LAST SIG_NAME SWB_HSC_PWRGD
J 0
(-2985 960);
DISPLAY 0.638298 (-2985 960);
WIRE 16 -1 (-1925 -1150)(-2100 -1150);
WIRE 16 -1 (-2100 -1000)(-2100 -1150);
WIRE 16 -1 (-2100 -1150)(-2100 -1300);
WIRE 16 -1 (-1925 -1300)(-2100 -1300);
WIRE 16 -1 (-2100 -1300)(-2100 -1600);
WIRE 16 -1 (-1925 -1000)(-2100 -1000);
WIRE 16 -1 (-2100 -1000)(-2100 -850);
WIRE 16 -1 (-1925 -850)(-2100 -850);
WIRE 16 -1 (-2100 -850)(-2100 -700);
WIRE 16 -1 (-1925 -700)(-2100 -700);
WIRE 16 -1 (-2100 -450)(-2100 -700);
WIRE 16 -1 (-1925 -450)(-2100 -450);
WIRE 16 -1 (-2100 -300)(-2100 -450);
WIRE 16 -1 (-1925 -300)(-2100 -300);
WIRE 16 -1 (-2100 -150)(-2100 -300);
WIRE 16 -1 (-2100 0)(-2100 -150);
WIRE 16 -1 (-1925 -150)(-2100 -150);
WIRE 16 -1 (-1925 0)(-2100 0);
WIRE 16 -1 (-2100 150)(-2100 0);
WIRE 16 -1 (-1925 150)(-2100 150);
WIRE 16 -1 (-2100 300)(-2100 150);
WIRE 16 -1 (-1925 300)(-2100 300);
WIRE 16 -1 (-2100 450)(-2100 300);
WIRE 16 -1 (-1925 450)(-2100 450);
WIRE 16 -1 (-2100 600)(-2100 450);
WIRE 16 -1 (-1925 600)(-2100 600);
WIRE 16 -1 (-2100 750)(-2100 600);
WIRE 16 -1 (-1925 750)(-2100 750);
WIRE 16 -1 (-2100 900)(-2100 750);
WIRE 16 -1 (-1925 900)(-2100 900);
WIRE 16 -1 (-2100 1150)(-2100 900);
WIRE 16 -1 (-1925 1150)(-2100 1150);
WIRE 16 -1 (-2100 1300)(-2100 1150);
WIRE 16 -1 (-1925 1300)(-2100 1300);
WIRE 16 -1 (-2100 1450)(-2100 1300);
WIRE 16 -1 (-1925 1450)(-2100 1450);
WIRE 16 -1 (-2100 1600)(-2100 1450);
WIRE 16 -1 (-1925 1600)(-2100 1600);
WIRE 16 -1 (-2100 1750)(-2100 1600);
WIRE 16 -1 (-1925 1750)(-2100 1750);
WIRE 16 -1 (2575 1200)(1325 1200);
FORCEPROP 2 LAST SIG_NAME P5E_CPU0_P1_TX_BUF_C_DP<11>
J 0
(1490 1210);
DISPLAY 0.638298 (1490 1210);
WIRE 16 -1 (2575 1250)(1325 1250);
FORCEPROP 2 LAST SIG_NAME P5E_CPU0_P1_TX_BUF_C_DN<11>
J 0
(1490 1260);
DISPLAY 0.638298 (1490 1260);
WIRE 16 -1 (2575 1350)(1325 1350);
FORCEPROP 2 LAST SIG_NAME P5E_CPU0_P0_TX_BUF_C_DP<11>
J 0
(1490 1360);
DISPLAY 0.638298 (1490 1360);
WIRE 16 -1 (2575 -1250)(1350 -1250);
FORCEPROP 2 LAST SIG_NAME P5E_CPU0_P1_TX_BUF_C_DP<8>
J 0
(1490 -1240);
DISPLAY 0.638298 (1490 -1240);
WIRE 16 -1 (2575 -1100)(1350 -1100);
FORCEPROP 2 LAST SIG_NAME P5E_CPU0_P0_TX_BUF_C_DP<8>
J 0
(1490 -1090);
DISPLAY 0.638298 (1490 -1090);
WIRE 16 -1 (2575 -950)(1350 -950);
FORCEPROP 2 LAST SIG_NAME P5E_CPU0_P1_RX_BUF_DP<8>
J 0
(1490 -940);
DISPLAY 0.638298 (1490 -940);
WIRE 16 -1 (2575 1400)(1325 1400);
FORCEPROP 2 LAST SIG_NAME P5E_CPU0_P0_TX_BUF_C_DN<11>
J 0
(1490 1410);
DISPLAY 0.638298 (1490 1410);
WIRE 16 -1 (2575 1500)(1325 1500);
FORCEPROP 2 LAST SIG_NAME P5E_CPU0_P1_RX_BUF_DP<11>
J 0
(1490 1510);
DISPLAY 0.638298 (1490 1510);
WIRE 16 -1 (-1925 -650)(-3150 -650);
FORCEPROP 2 LAST SIG_NAME NC_J107_A5
J 0
(-2985 -640);
DISPLAY 0.638298 (-2985 -640);
FORCEPROP 2 LASTPROP $XRERR UNIQUE?
J 0
(-3390 -650);
DISPLAY 0.638298 (-3390 -650);
PAINT MONO (-3390 -650);
DISPLAY INVISIBLE (-3390 -650);
WIRE 16 -1 (-1925 -1250)(-3150 -1250);
FORCEPROP 2 LAST SIG_NAME P5E_CPU0_P1_TX_BUF_C_DP<12>
J 0
(-2985 -1240);
DISPLAY 0.638298 (-2985 -1240);
WIRE 16 -1 (-1925 -1200)(-3150 -1200);
FORCEPROP 2 LAST SIG_NAME P5E_CPU0_P1_TX_BUF_C_DN<12>
J 0
(-2985 -1190);
DISPLAY 0.638298 (-2985 -1190);
WIRE 16 -1 (-1925 -1100)(-3150 -1100);
FORCEPROP 2 LAST SIG_NAME P5E_CPU0_P0_TX_BUF_C_DP<12>
J 0
(-2985 -1090);
DISPLAY 0.638298 (-2985 -1090);
WIRE 16 -1 (-1925 -1050)(-3150 -1050);
FORCEPROP 2 LAST SIG_NAME P5E_CPU0_P0_TX_BUF_C_DN<12>
J 0
(-2985 -1040);
DISPLAY 0.638298 (-2985 -1040);
WIRE 16 -1 (-1925 -350)(-3150 -350);
FORCEPROP 2 LAST SIG_NAME P5E_CPU0_P1_TX_BUF_C_DN<13>
J 0
(-2985 -340);
DISPLAY 0.638298 (-2985 -340);
WIRE 16 -1 (-1925 -250)(-3150 -250);
FORCEPROP 2 LAST SIG_NAME P5E_CPU0_P0_TX_BUF_C_DP<13>
J 0
(-2985 -240);
DISPLAY 0.638298 (-2985 -240);
WIRE 16 -1 (-1925 -100)(-3150 -100);
FORCEPROP 2 LAST SIG_NAME P5E_CPU0_P1_RX_BUF_DP<13>
J 0
(-2985 -90);
DISPLAY 0.638298 (-2985 -90);
WIRE 16 -1 (-1925 -50)(-3150 -50);
FORCEPROP 2 LAST SIG_NAME P5E_CPU0_P1_RX_BUF_DN<13>
J 0
(-2985 -40);
DISPLAY 0.638298 (-2985 -40);
WIRE 16 -1 (-1925 100)(-3150 100);
FORCEPROP 2 LAST SIG_NAME P5E_CPU0_P0_RX_BUF_DN<13>
J 0
(-2985 110);
DISPLAY 0.638298 (-2985 110);
WIRE 16 -1 (-1925 50)(-3150 50);
FORCEPROP 2 LAST SIG_NAME P5E_CPU0_P0_RX_BUF_DP<13>
J 0
(-2985 60);
DISPLAY 0.638298 (-2985 60);
WIRE 16 -1 (-1925 350)(-3150 350);
FORCEPROP 2 LAST SIG_NAME P5E_CPU0_P1_TX_BUF_C_DP<14>
J 0
(-2985 360);
DISPLAY 0.638298 (-2985 360);
WIRE 16 -1 (-1925 1100)(-3150 1100);
FORCEPROP 2 LAST SIG_NAME SWB_HSC_EN_BUF
J 0
(-2985 1110);
DISPLAY 0.638298 (-2985 1110);
WIRE 16 -1 (-1925 1200)(-3150 1200);
FORCEPROP 2 LAST SIG_NAME P5E_CPU0_P1_TX_BUF_C_DP<15>
J 0
(-2985 1210);
DISPLAY 0.638298 (-2985 1210);
WIRE 16 -1 (-1925 1250)(-3150 1250);
FORCEPROP 2 LAST SIG_NAME P5E_CPU0_P1_TX_BUF_C_DN<15>
J 0
(-2985 1260);
DISPLAY 0.638298 (-2985 1260);
WIRE 16 -1 (-1925 700)(-3150 700);
FORCEPROP 2 LAST SIG_NAME P5E_CPU0_P1_RX_BUF_DN<14>
J 0
(-2985 710);
DISPLAY 0.638298 (-2985 710);
WIRE 16 -1 (-1925 550)(-3150 550);
FORCEPROP 2 LAST SIG_NAME P5E_CPU0_P0_TX_BUF_C_DN<14>
J 0
(-2985 560);
DISPLAY 0.638298 (-2985 560);
WIRE 16 -1 (-1925 500)(-3150 500);
FORCEPROP 2 LAST SIG_NAME P5E_CPU0_P0_TX_BUF_C_DP<14>
J 0
(-2985 510);
DISPLAY 0.638298 (-2985 510);
WIRE 16 -1 (-1925 650)(-3150 650);
FORCEPROP 2 LAST SIG_NAME P5E_CPU0_P1_RX_BUF_DP<14>
J 0
(-2985 660);
DISPLAY 0.638298 (-2985 660);
WIRE 16 -1 (-1925 1350)(-3150 1350);
FORCEPROP 2 LAST SIG_NAME P5E_CPU0_P0_TX_BUF_C_DP<15>
J 0
(-2985 1360);
DISPLAY 0.638298 (-2985 1360);
WIRE 16 -1 (-1925 1400)(-3150 1400);
FORCEPROP 2 LAST SIG_NAME P5E_CPU0_P0_TX_BUF_C_DN<15>
J 0
(-2985 1410);
DISPLAY 0.638298 (-2985 1410);
WIRE 16 -1 (-1925 1500)(-3150 1500);
FORCEPROP 2 LAST SIG_NAME P5E_CPU0_P1_RX_BUF_DP<15>
J 0
(-2985 1510);
DISPLAY 0.638298 (-2985 1510);
WIRE 16 -1 (-1925 1550)(-3150 1550);
FORCEPROP 2 LAST SIG_NAME P5E_CPU0_P1_RX_BUF_DN<15>
J 0
(-2985 1560);
DISPLAY 0.638298 (-2985 1560);
WIRE 16 -1 (-1925 -800)(-3150 -800);
FORCEPROP 2 LAST SIG_NAME P5E_CPU0_P0_RX_BUF_DP<12>
J 0
(-2985 -790);
DISPLAY 0.638298 (-2985 -790);
WIRE 16 -1 (-1925 -900)(-3150 -900);
FORCEPROP 2 LAST SIG_NAME P5E_CPU0_P1_RX_BUF_DN<12>
J 0
(-2985 -890);
DISPLAY 0.638298 (-2985 -890);
WIRE 16 -1 (-1925 -950)(-3150 -950);
FORCEPROP 2 LAST SIG_NAME P5E_CPU0_P1_RX_BUF_DP<12>
J 0
(-2985 -940);
DISPLAY 0.638298 (-2985 -940);
WIRE 16 -1 (-1925 -500)(-3150 -500);
FORCEPROP 2 LAST SIG_NAME NC_J107_N6
J 0
(-2985 -490);
DISPLAY 0.638298 (-2985 -490);
FORCEPROP 2 LASTPROP $XRERR UNIQUE?
J 0
(-3390 -500);
DISPLAY 0.638298 (-3390 -500);
PAINT MONO (-3390 -500);
DISPLAY INVISIBLE (-3390 -500);
WIRE 16 -1 (-1925 400)(-3150 400);
FORCEPROP 2 LAST SIG_NAME P5E_CPU0_P1_TX_BUF_C_DN<14>
J 0
(-2985 410);
DISPLAY 0.638298 (-2985 410);
WIRE 16 -1 (-1925 -200)(-3150 -200);
FORCEPROP 2 LAST SIG_NAME P5E_CPU0_P0_TX_BUF_C_DN<13>
J 0
(-2985 -190);
DISPLAY 0.638298 (-2985 -190);
WIRE 16 -1 (2575 -1200)(1350 -1200);
FORCEPROP 2 LAST SIG_NAME P5E_CPU0_P1_TX_BUF_C_DN<8>
J 0
(1490 -1190);
DISPLAY 0.638298 (1490 -1190);
WIRE 16 -1 (2575 -1050)(1350 -1050);
FORCEPROP 2 LAST SIG_NAME P5E_CPU0_P0_TX_BUF_C_DN<8>
J 0
(1490 -1040);
DISPLAY 0.638298 (1490 -1040);
WIRE 16 -1 (2575 -900)(1350 -900);
FORCEPROP 2 LAST SIG_NAME P5E_CPU0_P1_RX_BUF_DN<8>
J 0
(1490 -890);
DISPLAY 0.638298 (1490 -890);
WIRE 16 -1 (2575 -200)(1350 -200);
FORCEPROP 2 LAST SIG_NAME P5E_CPU0_P0_TX_BUF_C_DN<9>
J 0
(1490 -190);
DISPLAY 0.638298 (1490 -190);
WIRE 16 -1 (2575 1550)(1325 1550);
FORCEPROP 2 LAST SIG_NAME P5E_CPU0_P1_RX_BUF_DN<11>
J 0
(1490 1560);
DISPLAY 0.638298 (1490 1560);
WIRE 16 -1 (-1925 -750)(-3150 -750);
FORCEPROP 2 LAST SIG_NAME P5E_CPU0_P0_RX_BUF_DN<12>
J 0
(-2985 -740);
DISPLAY 0.638298 (-2985 -740);
WIRE 16 -1 (-1925 1650)(-3150 1650);
FORCEPROP 2 LAST SIG_NAME P5E_CPU0_P0_RX_BUF_DP<15>
J 0
(-2985 1660);
DISPLAY 0.638298 (-2985 1660);
WIRE 16 -1 (-1925 1700)(-3150 1700);
FORCEPROP 2 LAST SIG_NAME P5E_CPU0_P0_RX_BUF_DN<15>
J 0
(-2985 1710);
DISPLAY 0.638298 (-2985 1710);
WIRE 16 -1 (2575 -800)(1350 -800);
FORCEPROP 2 LAST SIG_NAME P5E_CPU0_P0_RX_BUF_DP<8>
J 0
(1490 -790);
DISPLAY 0.638298 (1490 -790);
WIRE 16 -1 (2575 1650)(1325 1650);
FORCEPROP 2 LAST SIG_NAME P5E_CPU0_P0_RX_BUF_DP<11>
J 0
(1490 1660);
DISPLAY 0.638298 (1490 1660);
WIRE 16 -1 (2575 1700)(1325 1700);
FORCEPROP 2 LAST SIG_NAME P5E_CPU0_P0_RX_BUF_DN<11>
J 0
(1490 1710);
DISPLAY 0.638298 (1490 1710);
DOT 1 (2350 0);
DOT 1 (2350 150);
DOT 1 (2350 750);
DOT 1 (2350 600);
DOT 1 (-2100 1300);
DOT 1 (-2100 300);
DOT 1 (-2100 -1150);
DOT 1 (-2100 -1300);
DOT 1 (-2100 -1000);
DOT 1 (-2100 -300);
DOT 1 (-2100 -450);
DOT 1 (-2100 -150);
DOT 1 (-2100 0);
DOT 1 (-2100 150);
DOT 1 (-2100 450);
DOT 1 (-2100 750);
DOT 1 (-2100 1450);
DOT 1 (-2100 1600);
DOT 1 (2350 -1150);
DOT 1 (2350 -1300);
DOT 1 (2350 -850);
DOT 1 (2350 -1000);
DOT 1 (2350 -700);
DOT 1 (2350 -450);
DOT 1 (2350 -300);
DOT 1 (2350 -150);
DOT 1 (2350 300);
DOT 1 (2350 450);
DOT 1 (2350 1150);
DOT 1 (2350 1300);
DOT 1 (2350 1450);
DOT 1 (2350 1600);
DOT 1 (-2100 600);
DOT 1 (-2100 1150);
DOT 1 (-2100 900);
DOT 1 (-2100 -700);
DOT 1 (-2100 -850);
DOT 1 (2350 900);
FORCENOTE
CPU0_P1_TX/RX<0-15> LANE REVERSAL
(-4250 2250) 0;
DISPLAY LEFT (-4250 2250);
DISPLAY 1.595745 (-4250 2250);
PAINT PINK (-4250 2250);
FORCENOTE
CPU0_P0_TX/RX<0-15> LANE REVERSAL
(-4250 2350) 0;
DISPLAY LEFT (-4250 2350);
DISPLAY 1.595745 (-4250 2350);
PAINT PINK (-4250 2350);
QUIT
